FILE_TYPE = MACRO_DRAWING;
SET COLOR_WIRE YELLOW;
SET COLOR_PROP ORANGE;
SET COLOR_DOT WHITE;
SET COLOR_ARC YELLOW;
SET COLOR_BODY GREEN;
SET COLOR_NOTE PURPLE;
SET PROP_DISPLAY VALUE;
SET PAGE_NUMBER P276;
FORCEADD UNIVERSAL_GND..1
(-7825 3100);
FORCEPROP 3 LASTPIN (-7825 3150) SIG_NAME GND\g
J 0
(-7815 3160);
DISPLAY 0.659574 (-7815 3160);
PAINT MONO (-7815 3160);
DISPLAY INVISIBLE (-7815 3160);
FORCEPROP 1 LAST HDL_POWER GND
J 1
(-7800 3025);
DISPLAY 0.872340 (-7800 3025);
PAINT GREEN (-7800 3025);
DISPLAY INVISIBLE (-7800 3025);
FORCEPROP 2 LAST CDS_LIB logical_power
J 0
(-7825 3100);
PAINT MONO (-7825 3100);
DISPLAY INVISIBLE (-7825 3100);
FORCEPROP 1 LAST PATH I1
J 0
(-7750 3100);
DISPLAY 0.872340 (-7750 3100);
PAINT AQUA (-7750 3100);
DISPLAY INVISIBLE (-7750 3100);
FORCEADD OFFPAGE..5
(-7350 3825);
FORCEPROP 2 LAST $XR0 284 
J 0
(-7635 3825);
DISPLAY 0.638298 (-7635 3825);
PAINT MONO (-7635 3825);
FORCEPROP 1 LAST COMMENT_BODY TRUE
J 0
(-7250 3750);
DISPLAY 0.872340 (-7250 3750);
PAINT GREEN (-7250 3750);
DISPLAY INVISIBLE (-7250 3750);
FORCEPROP 1 LAST OFFPAGE TRUE
J 0
(-7025 3700);
DISPLAY 0.872340 (-7025 3700);
PAINT GREEN (-7025 3700);
DISPLAY INVISIBLE (-7025 3700);
FORCEPROP 2 LAST CDS_LIB standard
J 0
(-7350 3825);
DISPLAY INVISIBLE (-7350 3825);
FORCEPROP 2 LAST PATH I10
J 0
(-7625 3875);
DISPLAY 1.021277 (-7625 3875);
DISPLAY INVISIBLE (-7625 3875);
FORCEADD UNIVERSAL_GND..1
(-7325 4025);
FORCEPROP 3 LASTPIN (-7325 4075) SIG_NAME GND\g
J 0
(-7315 4085);
DISPLAY 0.659574 (-7315 4085);
PAINT MONO (-7315 4085);
DISPLAY INVISIBLE (-7315 4085);
FORCEPROP 1 LAST HDL_POWER GND
J 1
(-7300 3950);
DISPLAY 0.872340 (-7300 3950);
PAINT GREEN (-7300 3950);
DISPLAY INVISIBLE (-7300 3950);
FORCEPROP 2 LAST CDS_LIB logical_power
J 0
(-7325 4025);
PAINT MONO (-7325 4025);
DISPLAY INVISIBLE (-7325 4025);
FORCEPROP 1 LAST PATH I11
J 0
(-7250 4025);
DISPLAY 0.872340 (-7250 4025);
PAINT AQUA (-7250 4025);
DISPLAY INVISIBLE (-7250 4025);
FORCEADD Q_CAP..1
(-7325 4275);
FORCEPROP 1 LAST PART_NUMBER CH5222KEB01
J 0
(-7275 4100);
DISPLAY 0.617021 (-7275 4100);
PAINT BLUE (-7275 4100);
DISPLAY INVISIBLE (-7275 4100);
FORCEPROP 1 LAST MATERIAL X6S
J 0
(-7275 4200);
DISPLAY 0.617021 (-7275 4200);
PAINT SKYBLUE (-7275 4200);
FORCEPROP 1 LAST PACK_TYPE C0402
J 0
(-7275 4150);
DISPLAY 0.617021 (-7275 4150);
PAINT SKYBLUE (-7275 4150);
FORCEPROP 1 LAST TOLERANCE 10%
J 0
(-7275 4250);
DISPLAY 0.617021 (-7275 4250);
PAINT SKYBLUE (-7275 4250);
FORCEPROP 1 LAST VALUE 2.2UF
J 0
(-7275 4350);
DISPLAY 0.617021 (-7275 4350);
PAINT SKYBLUE (-7275 4350);
FORCEPROP 1 LAST VOLTAGE 10V
J 0
(-7275 4300);
DISPLAY 0.617021 (-7275 4300);
PAINT SKYBLUE (-7275 4300);
FORCEPROP 1 LAST LOCATION PC1192
J 0
(-7275 4400);
DISPLAY 0.617021 (-7275 4400);
PAINT AQUA (-7275 4400);
FORCEPROP 1 LASTPIN (-7325 4375) $PN 1
J 0
(-7315 4355);
DISPLAY 0.617021 (-7315 4355);
PAINT MONO (-7315 4355);
FORCEPROP 1 LASTPIN (-7325 4175) $PN 2
J 0
(-7315 4155);
DISPLAY 0.617021 (-7315 4155);
PAINT MONO (-7315 4155);
FORCEPROP 2 LAST CDS_LIB pure_quanta
J 0
(-7325 4275);
DISPLAY INVISIBLE (-7325 4275);
FORCEPROP 1 LAST PATH I12
J 0
(-7275 4425);
DISPLAY 0.978723 (-7275 4425);
PAINT WHITE (-7275 4425);
DISPLAY INVISIBLE (-7275 4425);
FORCEPROP 1 LAST LOCATION PC1192
J 0
(-7275 4450);
DISPLAY 1.021277 (-7275 4450);
PAINT AQUA (-7275 4450);
DISPLAY INVISIBLE (-7275 4450);
FORCEPROP 0 LAST $SEC 1
J 0
(-7275 4450);
DISPLAY 0.680851 (-7275 4450);
PAINT MONO (-7275 4450);
DISPLAY INVISIBLE (-7275 4450);
FORCEPROP 0 LAST CDS_SEC 1
J 0
(-7275 4450);
DISPLAY 1.021277 (-7275 4450);
DISPLAY INVISIBLE (-7275 4450);
FORCEADD Q_CAP..2
(-7050 3625);
FORCEPROP 1 LAST PART_NUMBER CH4104K1B00
J 1
(-6975 3675);
DISPLAY 0.617021 (-6975 3675);
PAINT BLUE (-6975 3675);
DISPLAY INVISIBLE (-6975 3675);
FORCEPROP 1 LAST MATERIAL X7R
J 0
(-6775 3675);
DISPLAY 0.617021 (-6775 3675);
PAINT SKYBLUE (-6775 3675);
FORCEPROP 1 LAST VOLTAGE 25V
J 0
(-6800 3625);
DISPLAY 0.617021 (-6800 3625);
PAINT SKYBLUE (-6800 3625);
FORCEPROP 1 LAST PACK_TYPE 0402
J 1
(-6600 3625);
DISPLAY 0.617021 (-6600 3625);
PAINT SKYBLUE (-6600 3625);
FORCEPROP 1 LAST VALUE 0.1UF
J 2
(-6825 3625);
DISPLAY 0.617021 (-6825 3625);
PAINT SKYBLUE (-6825 3625);
FORCEPROP 1 LAST TOLERANCE 10%
J 2
(-6550 3675);
DISPLAY 0.617021 (-6550 3675);
PAINT SKYBLUE (-6550 3675);
FORCEPROP 1 LAST LOCATION PC1370
J 1
(-7250 3625);
DISPLAY 0.617021 (-7250 3625);
PAINT AQUA (-7250 3625);
FORCEPROP 1 LASTPIN (-7150 3625) $PN 1
J 0
(-7160 3640);
DISPLAY 0.617021 (-7160 3640);
FORCEPROP 1 LASTPIN (-6950 3625) $PN 2
J 0
(-6965 3640);
DISPLAY 0.617021 (-6965 3640);
FORCEPROP 2 LAST CDS_LIB pure_quanta
J 0
(-7050 3625);
PAINT MONO (-7050 3625);
DISPLAY INVISIBLE (-7050 3625);
FORCEPROP 1 LAST PATH I13
J 0
(-7050 3825);
DISPLAY 0.978723 (-7050 3825);
PAINT WHITE (-7050 3825);
DISPLAY INVISIBLE (-7050 3825);
FORCEPROP 2 LAST $SEC 1
J 0
(-7050 3875);
DISPLAY 0.680851 (-7050 3875);
PAINT MONO (-7050 3875);
DISPLAY INVISIBLE (-7050 3875);
FORCEPROP 2 LAST CDS_SEC 1
J 0
(-7050 3875);
DISPLAY 1.021277 (-7050 3875);
DISPLAY INVISIBLE (-7050 3875);
FORCEADD UNIVERSAL_GND..1
(-6800 4425);
FORCEPROP 3 LASTPIN (-6800 4475) SIG_NAME GND\g
J 0
(-6790 4485);
DISPLAY 0.659574 (-6790 4485);
PAINT MONO (-6790 4485);
DISPLAY INVISIBLE (-6790 4485);
FORCEPROP 1 LAST HDL_POWER GND
J 1
(-6775 4350);
DISPLAY 0.872340 (-6775 4350);
PAINT GREEN (-6775 4350);
DISPLAY INVISIBLE (-6775 4350);
FORCEPROP 2 LAST CDS_LIB logical_power
J 0
(-6800 4425);
PAINT MONO (-6800 4425);
DISPLAY INVISIBLE (-6800 4425);
FORCEPROP 1 LAST PATH I14
J 0
(-6725 4425);
DISPLAY 0.872340 (-6725 4425);
PAINT AQUA (-6725 4425);
DISPLAY INVISIBLE (-6725 4425);
FORCEADD ISL99390FRZTR5935..1
(-5800 3825);
FORCEPROP 1 LAST PART_NUMBER AL099390004
J 0
(-6100 4625);
DISPLAY 0.617021 (-6100 4625);
PAINT BLUE (-6100 4625);
DISPLAY INVISIBLE (-6100 4625);
FORCEPROP 1 LAST MATERIAL IC
J 0
(-6100 4550);
DISPLAY 0.617021 (-6100 4550);
PAINT SKYBLUE (-6100 4550);
FORCEPROP 2 LAST VALUE ISL99390FRZ-TR5935
J 0
(-6100 4800);
DISPLAY 0.617021 (-6100 4800);
PAINT SKYBLUE (-6100 4800);
FORCEPROP 2 LAST PART_TYPE SMLF
J 0
(-6100 4850);
DISPLAY 0.808511 (-6100 4850);
FORCEPROP 1 LAST LOCATION PU78_P1_4
J 0
(-6100 4700);
DISPLAY 0.617021 (-6100 4700);
PAINT AQUA (-6100 4700);
FORCEPROP 2 LASTPIN (-5400 3375) $PN 2
J 0
(-5390 3385);
DISPLAY 0.617021 (-5390 3385);
PAINT MONO (-5390 3385);
FORCEPROP 2 LASTPIN (-5400 4175) $PN 33
J 0
(-5390 4185);
DISPLAY 0.617021 (-5390 4185);
PAINT MONO (-5390 4185);
FORCEPROP 2 LASTPIN (-6250 3575) $PN 31
J 2
(-6260 3585);
DISPLAY 0.617021 (-6260 3585);
PAINT MONO (-6260 3585);
FORCEPROP 2 LASTPIN (-6250 3975) $PN 35
J 2
(-6260 3985);
DISPLAY 0.617021 (-6260 3985);
PAINT MONO (-6260 3985);
FORCEPROP 2 LASTPIN (-5400 3525) $PN 6
J 0
(-5390 3535);
DISPLAY 0.617021 (-5390 3535);
PAINT MONO (-5390 3535);
FORCEPROP 2 LASTPIN (-5400 3475) $PN 41
J 0
(-5390 3485);
DISPLAY 0.617021 (-5390 3485);
PAINT MONO (-5390 3485);
FORCEPROP 2 LASTPIN (-6250 3825) $PN 38
J 2
(-6260 3835);
DISPLAY 0.617021 (-6260 3835);
PAINT MONO (-6260 3835);
FORCEPROP 2 LASTPIN (-6250 3525) $PN 37
J 2
(-6260 3535);
DISPLAY 0.617021 (-6260 3535);
PAINT MONO (-6260 3535);
FORCEPROP 2 LASTPIN (-5400 3325) $PN 5
J 0
(-5390 3335);
DISPLAY 0.617021 (-5390 3335);
PAINT MONO (-5390 3335);
FORCEPROP 2 LASTPIN (-5400 3275) $PN 7_9-20_24
J 0
(-5390 3285);
DISPLAY 0.617021 (-5390 3285);
PAINT MONO (-5390 3285);
FORCEPROP 2 LASTPIN (-5400 3225) $PN 40
J 0
(-5390 3235);
DISPLAY 0.617021 (-5390 3235);
PAINT MONO (-5390 3235);
FORCEPROP 2 LASTPIN (-5400 3925) $PN 32
J 0
(-5390 3935);
DISPLAY 0.617021 (-5390 3935);
PAINT MONO (-5390 3935);
FORCEPROP 2 LASTPIN (-6250 4475) $PN 4
J 2
(-6260 4485);
DISPLAY 0.617021 (-6260 4485);
PAINT MONO (-6260 4485);
FORCEPROP 2 LASTPIN (-6250 3225) $PN 34
J 2
(-6260 3235);
DISPLAY 0.617021 (-6260 3235);
PAINT MONO (-6260 3235);
FORCEPROP 2 LASTPIN (-6250 3725) $PN 39
J 2
(-6260 3735);
DISPLAY 0.617021 (-6260 3735);
PAINT MONO (-6260 3735);
FORCEPROP 2 LASTPIN (-5400 3825) $PN 10_19
J 0
(-5390 3835);
DISPLAY 0.617021 (-5390 3835);
PAINT MONO (-5390 3835);
FORCEPROP 2 LASTPIN (-6250 3325) $PN 36
J 2
(-6260 3335);
DISPLAY 0.617021 (-6260 3335);
PAINT MONO (-6260 3335);
FORCEPROP 2 LASTPIN (-6250 4175) $PN 3
J 2
(-6260 4185);
DISPLAY 0.617021 (-6260 4185);
PAINT MONO (-6260 4185);
FORCEPROP 2 LASTPIN (-5400 4475) $PN 25_29
J 0
(-5390 4485);
DISPLAY 0.617021 (-5390 4485);
PAINT MONO (-5390 4485);
FORCEPROP 2 LASTPIN (-5400 4425) $PN 30
J 0
(-5390 4435);
DISPLAY 0.617021 (-5390 4435);
PAINT MONO (-5390 4435);
FORCEPROP 2 LASTPIN (-5400 3575) $PN 1
J 0
(-5390 3585);
DISPLAY 0.617021 (-5390 3585);
PAINT MONO (-5390 3585);
FORCEPROP 1 LAST NEEDS_NO_SIZE TRUE
J 0
(-5800 3825);
DISPLAY 0.723404 (-5800 3825);
PAINT GREEN (-5800 3825);
DISPLAY INVISIBLE (-5800 3825);
FORCEPROP 1 LAST CDS_LMAN_SYM_OUTLINE -300,700,250,-650
J 0
(-5800 3825);
DISPLAY 0.468085 (-5800 3825);
PAINT GREEN (-5800 3825);
DISPLAY INVISIBLE (-5800 3825);
FORCEPROP 2 LAST CDS_LIB pure_quanta
J 0
(-5800 3825);
DISPLAY INVISIBLE (-5800 3825);
FORCEPROP 1 LAST PATH I15
J 0
(-5800 3825);
DISPLAY 0.723404 (-5800 3825);
PAINT GREEN (-5800 3825);
DISPLAY INVISIBLE (-5800 3825);
FORCEPROP 2 LAST $SEC 1
J 0
(-6100 4750);
DISPLAY 0.680851 (-6100 4750);
PAINT MONO (-6100 4750);
DISPLAY INVISIBLE (-6100 4750);
FORCEPROP 2 LAST CDS_SEC 1
J 0
(-6050 4825);
DISPLAY 1.021277 (-6050 4825);
DISPLAY INVISIBLE (-6050 4825);
FORCEADD UNIVERSAL_GND..1
(-5150 3100);
FORCEPROP 3 LASTPIN (-5150 3150) SIG_NAME GND\g
J 0
(-5140 3160);
DISPLAY 0.659574 (-5140 3160);
PAINT MONO (-5140 3160);
DISPLAY INVISIBLE (-5140 3160);
FORCEPROP 1 LAST HDL_POWER GND
J 1
(-5125 3025);
DISPLAY 0.872340 (-5125 3025);
PAINT GREEN (-5125 3025);
DISPLAY INVISIBLE (-5125 3025);
FORCEPROP 2 LAST CDS_LIB logical_power
J 0
(-5150 3100);
PAINT MONO (-5150 3100);
DISPLAY INVISIBLE (-5150 3100);
FORCEPROP 1 LAST PATH I16
J 0
(-5075 3100);
DISPLAY 0.872340 (-5075 3100);
PAINT AQUA (-5075 3100);
DISPLAY INVISIBLE (-5075 3100);
FORCEADD Q_RES..1
(-4300 4275);
FORCEPROP 1 LAST PART_NUMBER CS-3302FB01
J 0
(-4400 4325);
DISPLAY 0.617021 (-4400 4325);
PAINT BLUE (-4400 4325);
DISPLAY INVISIBLE (-4400 4325);
FORCEPROP 1 LAST WATTAGE 1/16W
J 2
(-4025 4350);
DISPLAY 0.617021 (-4025 4350);
PAINT SKYBLUE (-4025 4350);
FORCEPROP 1 LAST TOLERANCE 1%
J 0
(-4150 4275);
DISPLAY 0.617021 (-4150 4275);
PAINT SKYBLUE (-4150 4275);
FORCEPROP 1 LAST MATERIAL CHIP
J 0
(-4400 4375);
DISPLAY 0.617021 (-4400 4375);
PAINT SKYBLUE (-4400 4375);
FORCEPROP 1 LAST PACK_TYPE 0402LF
J 0
(-4400 4350);
DISPLAY 0.617021 (-4400 4350);
PAINT SKYBLUE (-4400 4350);
FORCEPROP 1 LAST VALUE 3.3
J 2
(-4175 4275);
DISPLAY 0.617021 (-4175 4275);
PAINT SKYBLUE (-4175 4275);
FORCEPROP 1 LAST LOCATION PR1803
J 0
(-4550 4275);
DISPLAY 0.617021 (-4550 4275);
PAINT AQUA (-4550 4275);
FORCEPROP 1 LASTPIN (-4400 4275) $PN 1
J 0
(-4388 4287);
DISPLAY 0.617021 (-4388 4287);
FORCEPROP 1 LASTPIN (-4200 4275) $PN 2
J 0
(-4238 4287);
DISPLAY 0.617021 (-4238 4287);
FORCEPROP 2 LAST CDS_LIB pure_quanta
J 0
(-4300 4275);
PAINT MONO (-4300 4275);
DISPLAY INVISIBLE (-4300 4275);
FORCEPROP 1 LAST PATH I17
J 0
(-4350 4425);
DISPLAY 0.978723 (-4350 4425);
PAINT WHITE (-4350 4425);
DISPLAY INVISIBLE (-4350 4425);
FORCEPROP 2 LAST $SEC 1
J 0
(-4350 4475);
DISPLAY 0.680851 (-4350 4475);
PAINT MONO (-4350 4475);
DISPLAY INVISIBLE (-4350 4475);
FORCEPROP 2 LAST CDS_SEC 1
J 0
(-4350 4475);
DISPLAY 1.021277 (-4350 4475);
DISPLAY INVISIBLE (-4350 4475);
FORCEADD Q_RES..2
(-7325 4675);
FORCEPROP 1 LAST PART_NUMBER CS-2202FB01
J 0
(-7285 4550);
DISPLAY 0.617021 (-7285 4550);
PAINT BLUE (-7285 4550);
DISPLAY INVISIBLE (-7285 4550);
FORCEPROP 1 LAST MATERIAL CHIP
J 0
(-7285 4600);
DISPLAY 0.617021 (-7285 4600);
PAINT SKYBLUE (-7285 4600);
FORCEPROP 1 LAST VALUE 2.2
J 0
(-7280 4750);
DISPLAY 0.617021 (-7280 4750);
PAINT SKYBLUE (-7280 4750);
FORCEPROP 1 LAST TOLERANCE 1%
J 0
(-7280 4700);
DISPLAY 0.617021 (-7280 4700);
PAINT SKYBLUE (-7280 4700);
FORCEPROP 1 LAST WATTAGE 1/16W
J 0
(-7285 4650);
DISPLAY 0.617021 (-7285 4650);
PAINT SKYBLUE (-7285 4650);
FORCEPROP 1 LAST PACK_TYPE 0402LF
J 0
(-7285 4500);
DISPLAY 0.617021 (-7285 4500);
PAINT SKYBLUE (-7285 4500);
FORCEPROP 1 LAST LOCATION PR1307
J 0
(-7280 4800);
DISPLAY 0.617021 (-7280 4800);
PAINT AQUA (-7280 4800);
FORCEPROP 1 LASTPIN (-7325 4775) $PN 1
J 0
(-7320 4737);
DISPLAY 0.617021 (-7320 4737);
PAINT MONO (-7320 4737);
FORCEPROP 1 LASTPIN (-7325 4575) $PN 2
J 0
(-7320 4585);
DISPLAY 0.617021 (-7320 4585);
PAINT MONO (-7320 4585);
FORCEPROP 2 LAST CDS_LIB pure_quanta
J 0
(-7325 4675);
DISPLAY INVISIBLE (-7325 4675);
FORCEPROP 1 LAST PATH I18
J 0
(-7275 4850);
DISPLAY 0.978723 (-7275 4850);
PAINT WHITE (-7275 4850);
DISPLAY INVISIBLE (-7275 4850);
FORCEPROP 0 LAST $SEC 1
J 0
(-7275 4850);
DISPLAY 0.680851 (-7275 4850);
PAINT MONO (-7275 4850);
DISPLAY INVISIBLE (-7275 4850);
FORCEPROP 0 LAST CDS_SEC 1
J 0
(-7275 4850);
DISPLAY 1.021277 (-7275 4850);
DISPLAY INVISIBLE (-7275 4850);
FORCEADD VCC15..1
(-7325 5000);
FORCEPROP 3 LASTPIN (-7325 4950) SIG_NAME PVCCFA_EHV_FIVRA_CPU1_PVCC2\g
J 0
(-7315 4960);
DISPLAY 0.659574 (-7315 4960);
PAINT MONO (-7315 4960);
DISPLAY INVISIBLE (-7315 4960);
FORCEPROP 1 LAST HDL_POWER PVCCFA_EHV_FIVRA_CPU1_PVCC2
J 1
(-7325 5050);
DISPLAY 0.617021 (-7325 5050);
PAINT GREEN (-7325 5050);
FORCEPROP 2 LAST CDS_LIB logical_power
J 0
(-7325 5000);
DISPLAY INVISIBLE (-7325 5000);
FORCEPROP 1 LAST PATH I19
J 0
(-7275 5025);
DISPLAY 0.872340 (-7275 5025);
PAINT AQUA (-7275 5025);
DISPLAY INVISIBLE (-7275 5025);
FORCEADD Q_RES..2
R 2
(-7825 3325);
FORCEPROP 1 LAST PART_NUMBER CS28872FB01
J 2
(-7875 3200);
DISPLAY 0.617021 (-7875 3200);
PAINT BLUE (-7875 3200);
DISPLAY INVISIBLE (-7875 3200);
FORCEPROP 1 LAST WATTAGE 1/16W
J 2
(-7875 3300);
DISPLAY 0.617021 (-7875 3300);
PAINT SKYBLUE (-7875 3300);
FORCEPROP 1 LAST MATERIAL EMPTY
J 2
(-7875 3250);
DISPLAY 0.617021 (-7875 3250);
PAINT RED (-7875 3250);
FORCEPROP 1 LAST TOLERANCE 1%
J 2
(-7880 3350);
DISPLAY 0.617021 (-7880 3350);
PAINT SKYBLUE (-7880 3350);
FORCEPROP 1 LAST VALUE 8.87K
J 2
(-7880 3400);
DISPLAY 0.617021 (-7880 3400);
PAINT SKYBLUE (-7880 3400);
FORCEPROP 1 LAST PACK_TYPE 0402LF
J 2
(-7875 3150);
DISPLAY 0.617021 (-7875 3150);
PAINT SKYBLUE (-7875 3150);
FORCEPROP 1 LAST LOCATION PR1304
J 2
(-7870 3450);
DISPLAY 0.617021 (-7870 3450);
PAINT AQUA (-7870 3450);
FORCEPROP 1 LASTPIN (-7825 3425) $PN 1
J 2
(-7830 3387);
DISPLAY 0.617021 (-7830 3387);
PAINT MONO (-7830 3387);
FORCEPROP 1 LASTPIN (-7825 3225) $PN 2
J 2
(-7830 3235);
DISPLAY 0.617021 (-7830 3235);
PAINT MONO (-7830 3235);
FORCEPROP 2 LAST CDS_LIB pure_quanta
J 2
(-7825 3325);
DISPLAY INVISIBLE (-7825 3325);
FORCEPROP 1 LAST PATH I2
J 2
(-7875 3500);
DISPLAY 0.978723 (-7875 3500);
PAINT WHITE (-7875 3500);
DISPLAY INVISIBLE (-7875 3500);
FORCEPROP 1 LAST LOCATION PR1304
J 2
(-7875 3500);
DISPLAY 1.021277 (-7875 3500);
PAINT AQUA (-7875 3500);
DISPLAY INVISIBLE (-7875 3500);
FORCEPROP 0 LAST $SEC 1
J 2
(-7875 3500);
DISPLAY 0.680851 (-7875 3500);
PAINT MONO (-7875 3500);
DISPLAY INVISIBLE (-7875 3500);
FORCEPROP 0 LAST CDS_SEC 1
J 2
(-7875 3500);
DISPLAY 1.021277 (-7875 3500);
DISPLAY INVISIBLE (-7875 3500);
FORCEADD Q_CAP..1
(-6800 4675);
FORCEPROP 1 LAST PART_NUMBER CH5222KEB01
J 0
(-6750 4525);
DISPLAY 0.617021 (-6750 4525);
PAINT BLUE (-6750 4525);
DISPLAY INVISIBLE (-6750 4525);
FORCEPROP 1 LAST VALUE 2.2UF
J 0
(-6750 4725);
DISPLAY 0.617021 (-6750 4725);
PAINT SKYBLUE (-6750 4725);
FORCEPROP 1 LAST MATERIAL X6S
J 0
(-6750 4575);
DISPLAY 0.617021 (-6750 4575);
PAINT SKYBLUE (-6750 4575);
FORCEPROP 1 LAST PACK_TYPE C0402
J 0
(-6750 4475);
DISPLAY 0.617021 (-6750 4475);
PAINT SKYBLUE (-6750 4475);
FORCEPROP 1 LAST VOLTAGE 10V
J 0
(-6750 4675);
DISPLAY 0.617021 (-6750 4675);
PAINT SKYBLUE (-6750 4675);
FORCEPROP 1 LAST TOLERANCE 10%
J 0
(-6750 4625);
DISPLAY 0.617021 (-6750 4625);
PAINT SKYBLUE (-6750 4625);
FORCEPROP 1 LAST LOCATION PC1245_P1_4
J 0
(-6750 4775);
DISPLAY 0.617021 (-6750 4775);
PAINT AQUA (-6750 4775);
FORCEPROP 1 LASTPIN (-6800 4775) $PN 1
J 0
(-6790 4755);
DISPLAY 0.617021 (-6790 4755);
FORCEPROP 1 LASTPIN (-6800 4575) $PN 2
J 0
(-6790 4555);
DISPLAY 0.617021 (-6790 4555);
FORCEPROP 2 LAST CDS_LIB pure_quanta
J 0
(-6800 4675);
PAINT MONO (-6800 4675);
DISPLAY INVISIBLE (-6800 4675);
FORCEPROP 1 LAST PATH I20
J 0
(-6750 4825);
DISPLAY 0.978723 (-6750 4825);
PAINT WHITE (-6750 4825);
DISPLAY INVISIBLE (-6750 4825);
FORCEPROP 2 LAST $SEC 1
J 0
(-6750 4875);
DISPLAY 0.680851 (-6750 4875);
PAINT MONO (-6750 4875);
DISPLAY INVISIBLE (-6750 4875);
FORCEPROP 2 LAST CDS_SEC 1
J 0
(-6750 4875);
DISPLAY 1.021277 (-6750 4875);
DISPLAY INVISIBLE (-6750 4875);
FORCEADD OFFPAGE..5
(-7325 6125);
FORCEPROP 2 LAST $XR2 284 
J 0
(-7610 6161);
DISPLAY 0.638298 (-7610 6161);
PAINT MONO (-7610 6161);
FORCEPROP 2 LAST $XR1 290 
J 0
(-7610 6089);
DISPLAY 0.638298 (-7610 6089);
PAINT MONO (-7610 6089);
FORCEPROP 2 LAST $XR0 289 
J 0
(-7610 6125);
DISPLAY 0.638298 (-7610 6125);
PAINT MONO (-7610 6125);
FORCEPROP 1 LAST COMMENT_BODY TRUE
J 0
(-7225 6050);
DISPLAY 0.872340 (-7225 6050);
PAINT GREEN (-7225 6050);
DISPLAY INVISIBLE (-7225 6050);
FORCEPROP 1 LAST OFFPAGE TRUE
J 0
(-7000 6000);
DISPLAY 0.872340 (-7000 6000);
PAINT GREEN (-7000 6000);
DISPLAY INVISIBLE (-7000 6000);
FORCEPROP 2 LAST CDS_LIB standard
J 0
(-7325 6125);
DISPLAY INVISIBLE (-7325 6125);
FORCEPROP 2 LAST PATH I21
J 0
(-7600 6200);
DISPLAY 1.021277 (-7600 6200);
DISPLAY INVISIBLE (-7600 6200);
FORCEADD OFFPAGE..1
(-7325 6025);
FORCEPROP 2 LAST $XR0 284 
J 0
(-7577 6025);
DISPLAY 0.638298 (-7577 6025);
PAINT MONO (-7577 6025);
FORCEPROP 1 LAST COMMENT_BODY TRUE
J 0
(-7200 5925);
DISPLAY 0.872340 (-7200 5925);
PAINT GREEN (-7200 5925);
DISPLAY INVISIBLE (-7200 5925);
FORCEPROP 1 LAST OFFPAGE TRUE
J 0
(-7000 5900);
DISPLAY 0.872340 (-7000 5900);
PAINT GREEN (-7000 5900);
DISPLAY INVISIBLE (-7000 5900);
FORCEPROP 2 LAST CDS_LIB standard
J 0
(-7325 6025);
DISPLAY INVISIBLE (-7325 6025);
FORCEPROP 2 LAST PATH I22
J 0
(-7575 6075);
DISPLAY 1.021277 (-7575 6075);
DISPLAY INVISIBLE (-7575 6075);
FORCEADD Q_CAP..2
(-7050 6425);
FORCEPROP 1 LAST PART_NUMBER CH4104K1B00
J 1
(-7025 6475);
DISPLAY 0.617021 (-7025 6475);
PAINT BLUE (-7025 6475);
DISPLAY INVISIBLE (-7025 6475);
FORCEPROP 1 LAST PACK_TYPE 0402
J 1
(-6600 6425);
DISPLAY 0.617021 (-6600 6425);
PAINT SKYBLUE (-6600 6425);
FORCEPROP 1 LAST TOLERANCE 10%
J 2
(-6575 6475);
DISPLAY 0.617021 (-6575 6475);
PAINT SKYBLUE (-6575 6475);
FORCEPROP 1 LAST MATERIAL X7R
J 0
(-6800 6475);
DISPLAY 0.617021 (-6800 6475);
PAINT SKYBLUE (-6800 6475);
FORCEPROP 1 LAST VOLTAGE 25V
J 0
(-6800 6425);
DISPLAY 0.617021 (-6800 6425);
PAINT SKYBLUE (-6800 6425);
FORCEPROP 1 LAST VALUE 0.1UF
J 2
(-6825 6425);
DISPLAY 0.617021 (-6825 6425);
PAINT SKYBLUE (-6825 6425);
FORCEPROP 1 LAST LOCATION PC1369
J 1
(-7250 6425);
DISPLAY 0.617021 (-7250 6425);
PAINT AQUA (-7250 6425);
FORCEPROP 1 LASTPIN (-7150 6425) $PN 1
J 0
(-7160 6440);
DISPLAY 0.617021 (-7160 6440);
FORCEPROP 1 LASTPIN (-6950 6425) $PN 2
J 0
(-6965 6440);
DISPLAY 0.617021 (-6965 6440);
FORCEPROP 2 LAST CDS_LIB pure_quanta
J 0
(-7050 6425);
PAINT MONO (-7050 6425);
DISPLAY INVISIBLE (-7050 6425);
FORCEPROP 1 LAST PATH I23
J 0
(-7050 6625);
DISPLAY 0.978723 (-7050 6625);
PAINT WHITE (-7050 6625);
DISPLAY INVISIBLE (-7050 6625);
FORCEPROP 2 LAST $SEC 1
J 0
(-7050 6675);
DISPLAY 0.680851 (-7050 6675);
PAINT MONO (-7050 6675);
DISPLAY INVISIBLE (-7050 6675);
FORCEPROP 2 LAST CDS_SEC 1
J 0
(-7050 6675);
DISPLAY 1.021277 (-7050 6675);
DISPLAY INVISIBLE (-7050 6675);
FORCEADD ISL99390FRZTR5935..1
(-5800 6625);
FORCEPROP 1 LAST PART_NUMBER AL099390004
J 0
(-6100 7425);
DISPLAY 0.617021 (-6100 7425);
PAINT BLUE (-6100 7425);
DISPLAY INVISIBLE (-6100 7425);
FORCEPROP 1 LAST MATERIAL IC
J 0
(-6100 7350);
DISPLAY 0.617021 (-6100 7350);
PAINT SKYBLUE (-6100 7350);
FORCEPROP 2 LAST PART_TYPE SMLF
J 0
(-6100 7525);
DISPLAY 0.808511 (-6100 7525);
FORCEPROP 2 LAST VALUE ISL99390FRZ-TR5935
J 0
(-6075 7375);
DISPLAY 0.617021 (-6075 7375);
PAINT SKYBLUE (-6075 7375);
FORCEPROP 1 LAST LOCATION PU77_P1_3
J 0
(-6100 7475);
DISPLAY 0.617021 (-6100 7475);
PAINT AQUA (-6100 7475);
FORCEPROP 2 LASTPIN (-5400 6175) $PN 2
J 0
(-5390 6185);
DISPLAY 0.617021 (-5390 6185);
PAINT MONO (-5390 6185);
FORCEPROP 2 LASTPIN (-5400 6975) $PN 33
J 0
(-5390 6985);
DISPLAY 0.617021 (-5390 6985);
PAINT MONO (-5390 6985);
FORCEPROP 2 LASTPIN (-6250 6375) $PN 31
J 2
(-6260 6385);
DISPLAY 0.617021 (-6260 6385);
PAINT MONO (-6260 6385);
FORCEPROP 2 LASTPIN (-6250 6775) $PN 35
J 2
(-6260 6785);
DISPLAY 0.617021 (-6260 6785);
PAINT MONO (-6260 6785);
FORCEPROP 2 LASTPIN (-5400 6325) $PN 6
J 0
(-5390 6335);
DISPLAY 0.617021 (-5390 6335);
PAINT MONO (-5390 6335);
FORCEPROP 2 LASTPIN (-5400 6275) $PN 41
J 0
(-5390 6285);
DISPLAY 0.617021 (-5390 6285);
PAINT MONO (-5390 6285);
FORCEPROP 2 LASTPIN (-6250 6625) $PN 38
J 2
(-6260 6635);
DISPLAY 0.617021 (-6260 6635);
PAINT MONO (-6260 6635);
FORCEPROP 2 LASTPIN (-6250 6325) $PN 37
J 2
(-6260 6335);
DISPLAY 0.617021 (-6260 6335);
PAINT MONO (-6260 6335);
FORCEPROP 2 LASTPIN (-5400 6125) $PN 5
J 0
(-5390 6135);
DISPLAY 0.617021 (-5390 6135);
PAINT MONO (-5390 6135);
FORCEPROP 2 LASTPIN (-5400 6075) $PN 7_9-20_24
J 0
(-5390 6085);
DISPLAY 0.617021 (-5390 6085);
PAINT MONO (-5390 6085);
FORCEPROP 2 LASTPIN (-5400 6025) $PN 40
J 0
(-5390 6035);
DISPLAY 0.617021 (-5390 6035);
PAINT MONO (-5390 6035);
FORCEPROP 2 LASTPIN (-5400 6725) $PN 32
J 0
(-5390 6735);
DISPLAY 0.617021 (-5390 6735);
PAINT MONO (-5390 6735);
FORCEPROP 2 LASTPIN (-6250 7275) $PN 4
J 2
(-6260 7285);
DISPLAY 0.617021 (-6260 7285);
PAINT MONO (-6260 7285);
FORCEPROP 2 LASTPIN (-6250 6025) $PN 34
J 2
(-6260 6035);
DISPLAY 0.617021 (-6260 6035);
PAINT MONO (-6260 6035);
FORCEPROP 2 LASTPIN (-6250 6525) $PN 39
J 2
(-6260 6535);
DISPLAY 0.617021 (-6260 6535);
PAINT MONO (-6260 6535);
FORCEPROP 2 LASTPIN (-5400 6625) $PN 10_19
J 0
(-5390 6635);
DISPLAY 0.617021 (-5390 6635);
PAINT MONO (-5390 6635);
FORCEPROP 2 LASTPIN (-6250 6125) $PN 36
J 2
(-6260 6135);
DISPLAY 0.617021 (-6260 6135);
PAINT MONO (-6260 6135);
FORCEPROP 2 LASTPIN (-6250 6975) $PN 3
J 2
(-6260 6985);
DISPLAY 0.617021 (-6260 6985);
PAINT MONO (-6260 6985);
FORCEPROP 2 LASTPIN (-5400 7275) $PN 25_29
J 0
(-5390 7285);
DISPLAY 0.617021 (-5390 7285);
PAINT MONO (-5390 7285);
FORCEPROP 2 LASTPIN (-5400 7225) $PN 30
J 0
(-5390 7235);
DISPLAY 0.617021 (-5390 7235);
PAINT MONO (-5390 7235);
FORCEPROP 2 LASTPIN (-5400 6375) $PN 1
J 0
(-5390 6385);
DISPLAY 0.617021 (-5390 6385);
PAINT MONO (-5390 6385);
FORCEPROP 1 LAST NEEDS_NO_SIZE TRUE
J 0
(-5800 6625);
DISPLAY 0.723404 (-5800 6625);
PAINT GREEN (-5800 6625);
DISPLAY INVISIBLE (-5800 6625);
FORCEPROP 1 LAST CDS_LMAN_SYM_OUTLINE -300,700,250,-650
J 0
(-5800 6625);
DISPLAY 0.468085 (-5800 6625);
PAINT GREEN (-5800 6625);
DISPLAY INVISIBLE (-5800 6625);
FORCEPROP 2 LAST CDS_LIB pure_quanta
J 0
(-5800 6625);
DISPLAY INVISIBLE (-5800 6625);
FORCEPROP 1 LAST PATH I24
J 0
(-5800 6625);
DISPLAY 0.723404 (-5800 6625);
PAINT GREEN (-5800 6625);
DISPLAY INVISIBLE (-5800 6625);
FORCEPROP 2 LAST $SEC 1
J 0
(-6100 7550);
DISPLAY 0.680851 (-6100 7550);
PAINT MONO (-6100 7550);
DISPLAY INVISIBLE (-6100 7550);
FORCEPROP 2 LAST CDS_SEC 1
J 0
(-6050 7625);
DISPLAY 1.021277 (-6050 7625);
DISPLAY INVISIBLE (-6050 7625);
FORCEADD OFFPAGE..1
(-7325 6525);
FORCEPROP 2 LAST $XR6 290 
J 0
(-8297 6525);
DISPLAY 0.638298 (-8297 6525);
PAINT MONO (-8297 6525);
FORCEPROP 2 LAST $XR5 289 
J 0
(-8177 6525);
DISPLAY 0.638298 (-8177 6525);
PAINT MONO (-8177 6525);
FORCEPROP 2 LAST $XR4 288 
J 0
(-8057 6525);
DISPLAY 0.638298 (-8057 6525);
PAINT MONO (-8057 6525);
FORCEPROP 2 LAST $XR3 287 
J 0
(-7937 6525);
DISPLAY 0.638298 (-7937 6525);
PAINT MONO (-7937 6525);
FORCEPROP 2 LAST $XR2 286 
J 0
(-7817 6525);
DISPLAY 0.638298 (-7817 6525);
PAINT MONO (-7817 6525);
FORCEPROP 2 LAST $XR1 285 
J 0
(-7697 6525);
DISPLAY 0.638298 (-7697 6525);
PAINT MONO (-7697 6525);
FORCEPROP 2 LAST $XR0 284 
J 0
(-7577 6525);
DISPLAY 0.638298 (-7577 6525);
PAINT MONO (-7577 6525);
FORCEPROP 1 LAST COMMENT_BODY TRUE
J 0
(-7200 6425);
DISPLAY 0.872340 (-7200 6425);
PAINT GREEN (-7200 6425);
DISPLAY INVISIBLE (-7200 6425);
FORCEPROP 1 LAST OFFPAGE TRUE
J 0
(-7000 6400);
DISPLAY 0.872340 (-7000 6400);
PAINT GREEN (-7000 6400);
DISPLAY INVISIBLE (-7000 6400);
FORCEPROP 2 LAST CDS_LIB standard
J 0
(-7325 6525);
DISPLAY INVISIBLE (-7325 6525);
FORCEPROP 2 LAST PATH I25
J 0
(-7575 6575);
DISPLAY 1.021277 (-7575 6575);
DISPLAY INVISIBLE (-7575 6575);
FORCEADD OFFPAGE..5
(-7325 6625);
FORCEPROP 2 LAST $XR0 284 
J 0
(-7610 6625);
DISPLAY 0.638298 (-7610 6625);
PAINT MONO (-7610 6625);
FORCEPROP 1 LAST COMMENT_BODY TRUE
J 0
(-7225 6550);
DISPLAY 0.872340 (-7225 6550);
PAINT GREEN (-7225 6550);
DISPLAY INVISIBLE (-7225 6550);
FORCEPROP 1 LAST OFFPAGE TRUE
J 0
(-7000 6500);
DISPLAY 0.872340 (-7000 6500);
PAINT GREEN (-7000 6500);
DISPLAY INVISIBLE (-7000 6500);
FORCEPROP 2 LAST CDS_LIB standard
J 0
(-7325 6625);
DISPLAY INVISIBLE (-7325 6625);
FORCEPROP 2 LAST PATH I26
J 0
(-7600 6675);
DISPLAY 1.021277 (-7600 6675);
DISPLAY INVISIBLE (-7600 6675);
FORCEADD Q_CAP..1
(-7325 7075);
FORCEPROP 1 LAST PART_NUMBER CH5222KEB01
J 0
(-7275 6900);
DISPLAY 0.617021 (-7275 6900);
PAINT BLUE (-7275 6900);
DISPLAY INVISIBLE (-7275 6900);
FORCEPROP 1 LAST MATERIAL X6S
J 0
(-7275 7000);
DISPLAY 0.617021 (-7275 7000);
PAINT SKYBLUE (-7275 7000);
FORCEPROP 1 LAST VOLTAGE 10V
J 0
(-7275 7100);
DISPLAY 0.617021 (-7275 7100);
PAINT SKYBLUE (-7275 7100);
FORCEPROP 1 LAST VALUE 2.2UF
J 0
(-7275 7150);
DISPLAY 0.617021 (-7275 7150);
PAINT SKYBLUE (-7275 7150);
FORCEPROP 1 LAST TOLERANCE 10%
J 0
(-7275 7050);
DISPLAY 0.617021 (-7275 7050);
PAINT SKYBLUE (-7275 7050);
FORCEPROP 1 LAST PACK_TYPE C0402
J 0
(-7275 6950);
DISPLAY 0.617021 (-7275 6950);
PAINT SKYBLUE (-7275 6950);
FORCEPROP 1 LAST LOCATION PC1191
J 0
(-7275 7200);
DISPLAY 0.617021 (-7275 7200);
PAINT AQUA (-7275 7200);
FORCEPROP 1 LASTPIN (-7325 7175) $PN 1
J 0
(-7315 7155);
DISPLAY 0.617021 (-7315 7155);
PAINT MONO (-7315 7155);
FORCEPROP 1 LASTPIN (-7325 6975) $PN 2
J 0
(-7315 6955);
DISPLAY 0.617021 (-7315 6955);
PAINT MONO (-7315 6955);
FORCEPROP 2 LAST CDS_LIB pure_quanta
J 0
(-7325 7075);
DISPLAY INVISIBLE (-7325 7075);
FORCEPROP 1 LAST PATH I27
J 0
(-7275 7225);
DISPLAY 0.978723 (-7275 7225);
PAINT WHITE (-7275 7225);
DISPLAY INVISIBLE (-7275 7225);
FORCEPROP 0 LAST $SEC 1
J 0
(-7275 7250);
DISPLAY 0.680851 (-7275 7250);
PAINT MONO (-7275 7250);
DISPLAY INVISIBLE (-7275 7250);
FORCEPROP 0 LAST CDS_SEC 1
J 0
(-7275 7250);
DISPLAY 1.021277 (-7275 7250);
DISPLAY INVISIBLE (-7275 7250);
FORCEADD UNIVERSAL_GND..1
(-7325 6825);
FORCEPROP 3 LASTPIN (-7325 6875) SIG_NAME GND\g
J 0
(-7315 6885);
DISPLAY 0.659574 (-7315 6885);
PAINT MONO (-7315 6885);
DISPLAY INVISIBLE (-7315 6885);
FORCEPROP 1 LAST HDL_POWER GND
J 1
(-7300 6750);
DISPLAY 0.872340 (-7300 6750);
PAINT GREEN (-7300 6750);
DISPLAY INVISIBLE (-7300 6750);
FORCEPROP 2 LAST CDS_LIB logical_power
J 0
(-7325 6825);
PAINT MONO (-7325 6825);
DISPLAY INVISIBLE (-7325 6825);
FORCEPROP 1 LAST PATH I28
J 0
(-7250 6825);
DISPLAY 0.872340 (-7250 6825);
PAINT AQUA (-7250 6825);
DISPLAY INVISIBLE (-7250 6825);
FORCEADD Q_RES..2
(-7325 7475);
FORCEPROP 1 LAST PART_NUMBER CS-2202FB01
J 0
(-7285 7350);
DISPLAY 0.617021 (-7285 7350);
PAINT BLUE (-7285 7350);
DISPLAY INVISIBLE (-7285 7350);
FORCEPROP 1 LAST MATERIAL CHIP
J 0
(-7285 7400);
DISPLAY 0.617021 (-7285 7400);
PAINT SKYBLUE (-7285 7400);
FORCEPROP 1 LAST WATTAGE 1/16W
J 0
(-7285 7450);
DISPLAY 0.617021 (-7285 7450);
PAINT SKYBLUE (-7285 7450);
FORCEPROP 1 LAST PACK_TYPE 0402LF
J 0
(-7285 7300);
DISPLAY 0.617021 (-7285 7300);
PAINT SKYBLUE (-7285 7300);
FORCEPROP 1 LAST TOLERANCE 1%
J 0
(-7280 7500);
DISPLAY 0.617021 (-7280 7500);
PAINT SKYBLUE (-7280 7500);
FORCEPROP 1 LAST VALUE 2.2
J 0
(-7280 7550);
DISPLAY 0.617021 (-7280 7550);
PAINT SKYBLUE (-7280 7550);
FORCEPROP 1 LAST LOCATION PR1306
J 0
(-7280 7600);
DISPLAY 0.617021 (-7280 7600);
PAINT AQUA (-7280 7600);
FORCEPROP 1 LASTPIN (-7325 7575) $PN 1
J 0
(-7320 7537);
DISPLAY 0.617021 (-7320 7537);
PAINT MONO (-7320 7537);
FORCEPROP 1 LASTPIN (-7325 7375) $PN 2
J 0
(-7320 7385);
DISPLAY 0.617021 (-7320 7385);
PAINT MONO (-7320 7385);
FORCEPROP 2 LAST CDS_LIB pure_quanta
J 0
(-7325 7475);
DISPLAY INVISIBLE (-7325 7475);
FORCEPROP 1 LAST PATH I29
J 0
(-7275 7650);
DISPLAY 0.978723 (-7275 7650);
PAINT WHITE (-7275 7650);
DISPLAY INVISIBLE (-7275 7650);
FORCEPROP 0 LAST $SEC 1
J 0
(-7275 7650);
DISPLAY 0.680851 (-7275 7650);
PAINT MONO (-7275 7650);
DISPLAY INVISIBLE (-7275 7650);
FORCEPROP 0 LAST CDS_SEC 1
J 0
(-7275 7650);
DISPLAY 1.021277 (-7275 7650);
DISPLAY INVISIBLE (-7275 7650);
FORCEADD UNIVERSAL_GND..1
(-7875 3525);
FORCEPROP 3 LASTPIN (-7875 3575) SIG_NAME GND\g
J 0
(-7865 3585);
DISPLAY 0.659574 (-7865 3585);
PAINT MONO (-7865 3585);
DISPLAY INVISIBLE (-7865 3585);
FORCEPROP 1 LAST HDL_POWER GND
J 1
(-7850 3450);
DISPLAY 0.872340 (-7850 3450);
PAINT GREEN (-7850 3450);
DISPLAY INVISIBLE (-7850 3450);
FORCEPROP 2 LAST CDS_LIB logical_power
J 0
(-7875 3525);
PAINT MONO (-7875 3525);
DISPLAY INVISIBLE (-7875 3525);
FORCEPROP 1 LAST PATH I3
J 0
(-7800 3525);
DISPLAY 0.872340 (-7800 3525);
PAINT AQUA (-7800 3525);
DISPLAY INVISIBLE (-7800 3525);
FORCEADD UNIVERSAL_GND..1
(-6800 7225);
FORCEPROP 3 LASTPIN (-6800 7275) SIG_NAME GND\g
J 0
(-6790 7285);
DISPLAY 0.659574 (-6790 7285);
PAINT MONO (-6790 7285);
DISPLAY INVISIBLE (-6790 7285);
FORCEPROP 1 LAST HDL_POWER GND
J 1
(-6775 7150);
DISPLAY 0.872340 (-6775 7150);
PAINT GREEN (-6775 7150);
DISPLAY INVISIBLE (-6775 7150);
FORCEPROP 2 LAST CDS_LIB logical_power
J 0
(-6800 7225);
PAINT MONO (-6800 7225);
DISPLAY INVISIBLE (-6800 7225);
FORCEPROP 1 LAST PATH I30
J 0
(-6725 7225);
DISPLAY 0.872340 (-6725 7225);
PAINT AQUA (-6725 7225);
DISPLAY INVISIBLE (-6725 7225);
FORCEADD Q_CAP..1
(-6800 7475);
FORCEPROP 1 LAST PART_NUMBER CH5222KEB01
J 0
(-6750 7325);
DISPLAY 0.617021 (-6750 7325);
PAINT BLUE (-6750 7325);
DISPLAY INVISIBLE (-6750 7325);
FORCEPROP 1 LAST MATERIAL X6S
J 0
(-6750 7375);
DISPLAY 0.617021 (-6750 7375);
PAINT SKYBLUE (-6750 7375);
FORCEPROP 1 LAST PACK_TYPE C0402
J 0
(-6750 7275);
DISPLAY 0.617021 (-6750 7275);
PAINT SKYBLUE (-6750 7275);
FORCEPROP 1 LAST VALUE 2.2UF
J 0
(-6750 7525);
DISPLAY 0.617021 (-6750 7525);
PAINT SKYBLUE (-6750 7525);
FORCEPROP 1 LAST TOLERANCE 10%
J 0
(-6750 7425);
DISPLAY 0.617021 (-6750 7425);
PAINT SKYBLUE (-6750 7425);
FORCEPROP 1 LAST VOLTAGE 10V
J 0
(-6750 7475);
DISPLAY 0.617021 (-6750 7475);
PAINT SKYBLUE (-6750 7475);
FORCEPROP 1 LAST LOCATION PC1244_P1_3
J 0
(-6750 7575);
DISPLAY 0.617021 (-6750 7575);
PAINT AQUA (-6750 7575);
FORCEPROP 1 LASTPIN (-6800 7575) $PN 1
J 0
(-6790 7555);
DISPLAY 0.617021 (-6790 7555);
FORCEPROP 1 LASTPIN (-6800 7375) $PN 2
J 0
(-6790 7355);
DISPLAY 0.617021 (-6790 7355);
FORCEPROP 2 LAST CDS_LIB pure_quanta
J 0
(-6800 7475);
PAINT MONO (-6800 7475);
DISPLAY INVISIBLE (-6800 7475);
FORCEPROP 1 LAST PATH I31
J 0
(-6750 7625);
DISPLAY 0.978723 (-6750 7625);
PAINT WHITE (-6750 7625);
DISPLAY INVISIBLE (-6750 7625);
FORCEPROP 2 LAST $SEC 1
J 0
(-6750 7675);
DISPLAY 0.680851 (-6750 7675);
PAINT MONO (-6750 7675);
DISPLAY INVISIBLE (-6750 7675);
FORCEPROP 2 LAST CDS_SEC 1
J 0
(-6750 7675);
DISPLAY 1.021277 (-6750 7675);
DISPLAY INVISIBLE (-6750 7675);
FORCEADD VCC15..1
(-7325 7800);
FORCEPROP 3 LASTPIN (-7325 7750) SIG_NAME PVCCFA_EHV_FIVRA_CPU1_PVCC1\g
J 0
(-7315 7760);
DISPLAY 0.659574 (-7315 7760);
PAINT MONO (-7315 7760);
DISPLAY INVISIBLE (-7315 7760);
FORCEPROP 1 LAST HDL_POWER PVCCFA_EHV_FIVRA_CPU1_PVCC1
J 1
(-7325 7850);
DISPLAY 0.617021 (-7325 7850);
PAINT GREEN (-7325 7850);
FORCEPROP 2 LAST CDS_LIB logical_power
J 0
(-7325 7800);
DISPLAY INVISIBLE (-7325 7800);
FORCEPROP 1 LAST PATH I32
J 0
(-7275 7825);
DISPLAY 0.872340 (-7275 7825);
PAINT AQUA (-7275 7825);
DISPLAY INVISIBLE (-7275 7825);
FORCEADD Q_CAP..1
(-5000 4725);
FORCEPROP 1 LAST PART_NUMBER TMP_QCH2336K1B12
J 0
(-4950 4575);
DISPLAY 0.617021 (-4950 4575);
PAINT BLUE (-4950 4575);
DISPLAY INVISIBLE (-4950 4575);
FORCEPROP 1 LAST VOLTAGE 50V
J 0
(-4950 4775);
DISPLAY 0.617021 (-4950 4775);
PAINT SKYBLUE (-4950 4775);
FORCEPROP 1 LAST PACK_TYPE 0402
J 0
(-4950 4625);
DISPLAY 0.617021 (-4950 4625);
PAINT SKYBLUE (-4950 4625);
FORCEPROP 1 LAST MATERIAL X7R
J 0
(-4950 4675);
DISPLAY 0.617021 (-4950 4675);
PAINT SKYBLUE (-4950 4675);
FORCEPROP 1 LAST TOLERANCE 10%
J 0
(-4950 4725);
DISPLAY 0.617021 (-4950 4725);
PAINT SKYBLUE (-4950 4725);
FORCEPROP 1 LAST VALUE 3300PF
J 0
(-4950 4825);
DISPLAY 0.617021 (-4950 4825);
PAINT SKYBLUE (-4950 4825);
FORCEPROP 1 LAST LOCATION PC1194_P1_4
J 0
(-4950 4875);
DISPLAY 0.617021 (-4950 4875);
PAINT AQUA (-4950 4875);
FORCEPROP 1 LASTPIN (-5000 4825) $PN 1
J 0
(-4990 4805);
DISPLAY 0.617021 (-4990 4805);
PAINT MONO (-4990 4805);
FORCEPROP 1 LASTPIN (-5000 4625) $PN 2
J 0
(-4990 4605);
DISPLAY 0.617021 (-4990 4605);
PAINT MONO (-4990 4605);
FORCEPROP 2 LAST CDS_LIB pure_quanta
J 0
(-5000 4725);
DISPLAY INVISIBLE (-5000 4725);
FORCEPROP 1 LAST PATH I33
J 0
(-4950 4875);
DISPLAY 0.978723 (-4950 4875);
PAINT WHITE (-4950 4875);
DISPLAY INVISIBLE (-4950 4875);
FORCEPROP 1 LAST LOCATION PC1194_P1_4
J 0
(-4950 4925);
DISPLAY 1.021277 (-4950 4925);
PAINT AQUA (-4950 4925);
DISPLAY INVISIBLE (-4950 4925);
FORCEPROP 0 LAST $SEC 1
J 0
(-4950 4925);
DISPLAY 0.680851 (-4950 4925);
PAINT MONO (-4950 4925);
DISPLAY INVISIBLE (-4950 4925);
FORCEPROP 0 LAST CDS_SEC 1
J 0
(-4950 4925);
DISPLAY 1.021277 (-4950 4925);
DISPLAY INVISIBLE (-4950 4925);
FORCEADD UNIVERSAL_GND..1
(-5150 5900);
FORCEPROP 3 LASTPIN (-5150 5950) SIG_NAME GND\g
J 0
(-5140 5960);
DISPLAY 0.659574 (-5140 5960);
PAINT MONO (-5140 5960);
DISPLAY INVISIBLE (-5140 5960);
FORCEPROP 1 LAST HDL_POWER GND
J 1
(-5125 5825);
DISPLAY 0.872340 (-5125 5825);
PAINT GREEN (-5125 5825);
DISPLAY INVISIBLE (-5125 5825);
FORCEPROP 2 LAST CDS_LIB logical_power
J 0
(-5150 5900);
PAINT MONO (-5150 5900);
DISPLAY INVISIBLE (-5150 5900);
FORCEPROP 1 LAST PATH I34
J 0
(-5075 5900);
DISPLAY 0.872340 (-5075 5900);
PAINT AQUA (-5075 5900);
DISPLAY INVISIBLE (-5075 5900);
FORCEADD Q_CAP..1
(-4600 4725);
FORCEPROP 1 LAST PART_NUMBER CH5103KEB01
J 0
(-4550 4575);
DISPLAY 0.617021 (-4550 4575);
PAINT BLUE (-4550 4575);
DISPLAY INVISIBLE (-4550 4575);
FORCEPROP 1 LAST VOLTAGE 16V
J 0
(-4550 4775);
DISPLAY 0.617021 (-4550 4775);
PAINT SKYBLUE (-4550 4775);
FORCEPROP 1 LAST TOLERANCE 10%
J 0
(-4550 4725);
DISPLAY 0.617021 (-4550 4725);
PAINT SKYBLUE (-4550 4725);
FORCEPROP 1 LAST PACK_TYPE C0402
J 0
(-4550 4625);
DISPLAY 0.617021 (-4550 4625);
PAINT SKYBLUE (-4550 4625);
FORCEPROP 1 LAST MATERIAL X6S
J 0
(-4550 4675);
DISPLAY 0.617021 (-4550 4675);
PAINT SKYBLUE (-4550 4675);
FORCEPROP 1 LAST VALUE 1UF
J 0
(-4550 4825);
DISPLAY 0.617021 (-4550 4825);
PAINT SKYBLUE (-4550 4825);
FORCEPROP 1 LAST LOCATION PC1196_P1_4
J 0
(-4550 4875);
DISPLAY 0.617021 (-4550 4875);
PAINT AQUA (-4550 4875);
FORCEPROP 1 LASTPIN (-4600 4825) $PN 1
J 0
(-4590 4805);
DISPLAY 0.617021 (-4590 4805);
PAINT MONO (-4590 4805);
FORCEPROP 1 LASTPIN (-4600 4625) $PN 2
J 0
(-4590 4605);
DISPLAY 0.617021 (-4590 4605);
PAINT MONO (-4590 4605);
FORCEPROP 2 LAST CDS_LIB pure_quanta
J 0
(-4600 4725);
DISPLAY INVISIBLE (-4600 4725);
FORCEPROP 1 LAST PATH I35
J 0
(-4550 4875);
DISPLAY 0.978723 (-4550 4875);
PAINT WHITE (-4550 4875);
DISPLAY INVISIBLE (-4550 4875);
FORCEPROP 1 LAST LOCATION PC1196_P1_4
J 0
(-4550 4925);
DISPLAY 1.021277 (-4550 4925);
PAINT AQUA (-4550 4925);
DISPLAY INVISIBLE (-4550 4925);
FORCEPROP 0 LAST $SEC 1
J 0
(-4550 4925);
DISPLAY 0.680851 (-4550 4925);
PAINT MONO (-4550 4925);
DISPLAY INVISIBLE (-4550 4925);
FORCEPROP 0 LAST CDS_SEC 1
J 0
(-4550 4925);
DISPLAY 1.021277 (-4550 4925);
DISPLAY INVISIBLE (-4550 4925);
FORCEADD Q_CAP..1
(-4200 4725);
FORCEPROP 1 LAST PART_NUMBER CH6223MEA01
J 0
(-4150 4575);
DISPLAY 0.617021 (-4150 4575);
PAINT BLUE (-4150 4575);
DISPLAY INVISIBLE (-4150 4575);
FORCEPROP 1 LAST TOLERANCE 20%
J 0
(-4150 4725);
DISPLAY 0.617021 (-4150 4725);
PAINT SKYBLUE (-4150 4725);
FORCEPROP 1 LAST MATERIAL X6S
J 0
(-4150 4675);
DISPLAY 0.617021 (-4150 4675);
PAINT SKYBLUE (-4150 4675);
FORCEPROP 1 LAST VALUE 22UF
J 0
(-4150 4825);
DISPLAY 0.617021 (-4150 4825);
PAINT SKYBLUE (-4150 4825);
FORCEPROP 1 LAST PACK_TYPE C0805
J 0
(-4150 4625);
DISPLAY 0.617021 (-4150 4625);
PAINT SKYBLUE (-4150 4625);
FORCEPROP 1 LAST VOLTAGE 16V
J 0
(-4150 4775);
DISPLAY 0.617021 (-4150 4775);
PAINT SKYBLUE (-4150 4775);
FORCEPROP 1 LAST LOCATION PC1200_P1_4
J 0
(-4150 4875);
DISPLAY 0.617021 (-4150 4875);
PAINT AQUA (-4150 4875);
FORCEPROP 1 LASTPIN (-4200 4825) $PN 1
J 0
(-4190 4805);
DISPLAY 0.617021 (-4190 4805);
PAINT MONO (-4190 4805);
FORCEPROP 1 LASTPIN (-4200 4625) $PN 2
J 0
(-4190 4605);
DISPLAY 0.617021 (-4190 4605);
PAINT MONO (-4190 4605);
FORCEPROP 2 LAST CDS_LIB pure_quanta
J 0
(-4200 4725);
DISPLAY INVISIBLE (-4200 4725);
FORCEPROP 1 LAST PATH I36
J 0
(-4150 4875);
DISPLAY 0.978723 (-4150 4875);
PAINT WHITE (-4150 4875);
DISPLAY INVISIBLE (-4150 4875);
FORCEPROP 1 LAST LOCATION PC1200_P1_4
J 0
(-4150 4925);
DISPLAY 1.021277 (-4150 4925);
PAINT AQUA (-4150 4925);
DISPLAY INVISIBLE (-4150 4925);
FORCEPROP 0 LAST $SEC 1
J 0
(-4150 4925);
DISPLAY 0.680851 (-4150 4925);
PAINT MONO (-4150 4925);
DISPLAY INVISIBLE (-4150 4925);
FORCEPROP 0 LAST CDS_SEC 1
J 0
(-4150 4925);
DISPLAY 1.021277 (-4150 4925);
DISPLAY INVISIBLE (-4150 4925);
FORCEADD Q_CAP..1
(-3800 4725);
FORCEPROP 1 LAST PART_NUMBER CH6223MEA01
J 0
(-3750 4575);
DISPLAY 0.617021 (-3750 4575);
PAINT BLUE (-3750 4575);
DISPLAY INVISIBLE (-3750 4575);
FORCEPROP 1 LAST TOLERANCE 20%
J 0
(-3750 4725);
DISPLAY 0.617021 (-3750 4725);
PAINT SKYBLUE (-3750 4725);
FORCEPROP 1 LAST VALUE 22UF
J 0
(-3750 4825);
DISPLAY 0.617021 (-3750 4825);
PAINT SKYBLUE (-3750 4825);
FORCEPROP 1 LAST PACK_TYPE C0805
J 0
(-3750 4625);
DISPLAY 0.617021 (-3750 4625);
PAINT SKYBLUE (-3750 4625);
FORCEPROP 1 LAST VOLTAGE 16V
J 0
(-3750 4775);
DISPLAY 0.617021 (-3750 4775);
PAINT SKYBLUE (-3750 4775);
FORCEPROP 1 LAST MATERIAL X6S
J 0
(-3750 4675);
DISPLAY 0.617021 (-3750 4675);
PAINT SKYBLUE (-3750 4675);
FORCEPROP 1 LAST LOCATION PC1202_P1_4
J 0
(-3750 4875);
DISPLAY 0.617021 (-3750 4875);
PAINT AQUA (-3750 4875);
FORCEPROP 1 LASTPIN (-3800 4825) $PN 1
J 0
(-3790 4805);
DISPLAY 0.617021 (-3790 4805);
PAINT MONO (-3790 4805);
FORCEPROP 1 LASTPIN (-3800 4625) $PN 2
J 0
(-3790 4605);
DISPLAY 0.617021 (-3790 4605);
PAINT MONO (-3790 4605);
FORCEPROP 2 LAST CDS_LIB pure_quanta
J 0
(-3800 4725);
DISPLAY INVISIBLE (-3800 4725);
FORCEPROP 1 LAST PATH I37
J 0
(-3750 4875);
DISPLAY 0.978723 (-3750 4875);
PAINT WHITE (-3750 4875);
DISPLAY INVISIBLE (-3750 4875);
FORCEPROP 1 LAST LOCATION PC1202_P1_4
J 0
(-3750 4925);
DISPLAY 1.021277 (-3750 4925);
PAINT AQUA (-3750 4925);
DISPLAY INVISIBLE (-3750 4925);
FORCEPROP 0 LAST $SEC 1
J 0
(-3750 4925);
DISPLAY 0.680851 (-3750 4925);
PAINT MONO (-3750 4925);
DISPLAY INVISIBLE (-3750 4925);
FORCEPROP 0 LAST CDS_SEC 1
J 0
(-3750 4925);
DISPLAY 1.021277 (-3750 4925);
DISPLAY INVISIBLE (-3750 4925);
FORCEADD Q_CAP..1
(-5000 7525);
FORCEPROP 1 LAST PART_NUMBER TMP_QCH2336K1B12
J 0
(-4950 7375);
DISPLAY 0.617021 (-4950 7375);
PAINT BLUE (-4950 7375);
DISPLAY INVISIBLE (-4950 7375);
FORCEPROP 1 LAST MATERIAL X7R
J 0
(-4950 7475);
DISPLAY 0.617021 (-4950 7475);
PAINT SKYBLUE (-4950 7475);
FORCEPROP 1 LAST PACK_TYPE 0402
J 0
(-4950 7425);
DISPLAY 0.617021 (-4950 7425);
PAINT SKYBLUE (-4950 7425);
FORCEPROP 1 LAST TOLERANCE 10%
J 0
(-4950 7525);
DISPLAY 0.617021 (-4950 7525);
PAINT SKYBLUE (-4950 7525);
FORCEPROP 1 LAST VOLTAGE 50V
J 0
(-4950 7575);
DISPLAY 0.617021 (-4950 7575);
PAINT SKYBLUE (-4950 7575);
FORCEPROP 1 LAST VALUE 3300PF
J 0
(-4950 7625);
DISPLAY 0.617021 (-4950 7625);
PAINT SKYBLUE (-4950 7625);
FORCEPROP 1 LAST LOCATION PC1193_P1_3
J 0
(-4950 7675);
DISPLAY 0.617021 (-4950 7675);
PAINT AQUA (-4950 7675);
FORCEPROP 1 LASTPIN (-5000 7625) $PN 1
J 0
(-4990 7605);
DISPLAY 0.617021 (-4990 7605);
PAINT MONO (-4990 7605);
FORCEPROP 1 LASTPIN (-5000 7425) $PN 2
J 0
(-4990 7405);
DISPLAY 0.617021 (-4990 7405);
PAINT MONO (-4990 7405);
FORCEPROP 2 LAST CDS_LIB pure_quanta
J 0
(-5000 7525);
DISPLAY INVISIBLE (-5000 7525);
FORCEPROP 1 LAST PATH I38
J 0
(-4950 7675);
DISPLAY 0.978723 (-4950 7675);
PAINT WHITE (-4950 7675);
DISPLAY INVISIBLE (-4950 7675);
FORCEPROP 1 LAST LOCATION PC1193_P1_3
J 0
(-4950 7725);
DISPLAY 1.021277 (-4950 7725);
PAINT AQUA (-4950 7725);
DISPLAY INVISIBLE (-4950 7725);
FORCEPROP 0 LAST $SEC 1
J 0
(-4950 7725);
DISPLAY 0.680851 (-4950 7725);
PAINT MONO (-4950 7725);
DISPLAY INVISIBLE (-4950 7725);
FORCEPROP 0 LAST CDS_SEC 1
J 0
(-4950 7725);
DISPLAY 1.021277 (-4950 7725);
DISPLAY INVISIBLE (-4950 7725);
FORCEADD Q_CAP..1
(-4600 7525);
FORCEPROP 1 LAST PART_NUMBER CH5103KEB01
J 0
(-4550 7375);
DISPLAY 0.617021 (-4550 7375);
PAINT BLUE (-4550 7375);
DISPLAY INVISIBLE (-4550 7375);
FORCEPROP 1 LAST MATERIAL X6S
J 0
(-4550 7475);
DISPLAY 0.617021 (-4550 7475);
PAINT SKYBLUE (-4550 7475);
FORCEPROP 1 LAST VALUE 1UF
J 0
(-4550 7625);
DISPLAY 0.617021 (-4550 7625);
PAINT SKYBLUE (-4550 7625);
FORCEPROP 1 LAST TOLERANCE 10%
J 0
(-4550 7525);
DISPLAY 0.617021 (-4550 7525);
PAINT SKYBLUE (-4550 7525);
FORCEPROP 1 LAST PACK_TYPE C0402
J 0
(-4550 7425);
DISPLAY 0.617021 (-4550 7425);
PAINT SKYBLUE (-4550 7425);
FORCEPROP 1 LAST VOLTAGE 16V
J 0
(-4550 7575);
DISPLAY 0.617021 (-4550 7575);
PAINT SKYBLUE (-4550 7575);
FORCEPROP 1 LAST LOCATION PC1195_P1_3
J 0
(-4550 7675);
DISPLAY 0.617021 (-4550 7675);
PAINT AQUA (-4550 7675);
FORCEPROP 1 LASTPIN (-4600 7625) $PN 1
J 0
(-4590 7605);
DISPLAY 0.617021 (-4590 7605);
PAINT MONO (-4590 7605);
FORCEPROP 1 LASTPIN (-4600 7425) $PN 2
J 0
(-4590 7405);
DISPLAY 0.617021 (-4590 7405);
PAINT MONO (-4590 7405);
FORCEPROP 2 LAST CDS_LIB pure_quanta
J 0
(-4600 7525);
DISPLAY INVISIBLE (-4600 7525);
FORCEPROP 1 LAST PATH I39
J 0
(-4550 7675);
DISPLAY 0.978723 (-4550 7675);
PAINT WHITE (-4550 7675);
DISPLAY INVISIBLE (-4550 7675);
FORCEPROP 1 LAST LOCATION PC1195_P1_3
J 0
(-4550 7725);
DISPLAY 1.021277 (-4550 7725);
PAINT AQUA (-4550 7725);
DISPLAY INVISIBLE (-4550 7725);
FORCEPROP 0 LAST $SEC 1
J 0
(-4550 7725);
DISPLAY 0.680851 (-4550 7725);
PAINT MONO (-4550 7725);
DISPLAY INVISIBLE (-4550 7725);
FORCEPROP 0 LAST CDS_SEC 1
J 0
(-4550 7725);
DISPLAY 1.021277 (-4550 7725);
DISPLAY INVISIBLE (-4550 7725);
FORCEADD UNIVERSAL_GND..1
(-7800 5900);
FORCEPROP 3 LASTPIN (-7800 5950) SIG_NAME GND\g
J 0
(-7790 5960);
DISPLAY 0.659574 (-7790 5960);
PAINT MONO (-7790 5960);
DISPLAY INVISIBLE (-7790 5960);
FORCEPROP 1 LAST HDL_POWER GND
J 1
(-7775 5825);
DISPLAY 0.872340 (-7775 5825);
PAINT GREEN (-7775 5825);
DISPLAY INVISIBLE (-7775 5825);
FORCEPROP 2 LAST CDS_LIB logical_power
J 0
(-7800 5900);
PAINT MONO (-7800 5900);
DISPLAY INVISIBLE (-7800 5900);
FORCEPROP 1 LAST PATH I4
J 0
(-7725 5900);
DISPLAY 0.872340 (-7725 5900);
PAINT AQUA (-7725 5900);
DISPLAY INVISIBLE (-7725 5900);
FORCEADD Q_RES..1
(-4300 7075);
FORCEPROP 1 LAST PART_NUMBER CS-3302FB01
J 0
(-4400 7125);
DISPLAY 0.617021 (-4400 7125);
PAINT BLUE (-4400 7125);
DISPLAY INVISIBLE (-4400 7125);
FORCEPROP 1 LAST WATTAGE 1/16W
J 2
(-4025 7150);
DISPLAY 0.617021 (-4025 7150);
PAINT SKYBLUE (-4025 7150);
FORCEPROP 1 LAST TOLERANCE 1%
J 0
(-4150 7075);
DISPLAY 0.617021 (-4150 7075);
PAINT SKYBLUE (-4150 7075);
FORCEPROP 1 LAST PACK_TYPE 0402LF
J 0
(-4400 7150);
DISPLAY 0.617021 (-4400 7150);
PAINT SKYBLUE (-4400 7150);
FORCEPROP 1 LAST VALUE 3.3
J 2
(-4175 7075);
DISPLAY 0.617021 (-4175 7075);
PAINT SKYBLUE (-4175 7075);
FORCEPROP 1 LAST MATERIAL CHIP
J 0
(-4400 7175);
DISPLAY 0.617021 (-4400 7175);
PAINT SKYBLUE (-4400 7175);
FORCEPROP 1 LAST LOCATION PR1802
J 0
(-4550 7075);
DISPLAY 0.617021 (-4550 7075);
PAINT AQUA (-4550 7075);
FORCEPROP 1 LASTPIN (-4400 7075) $PN 1
J 0
(-4388 7087);
DISPLAY 0.617021 (-4388 7087);
FORCEPROP 1 LASTPIN (-4200 7075) $PN 2
J 0
(-4238 7087);
DISPLAY 0.617021 (-4238 7087);
FORCEPROP 2 LAST CDS_LIB pure_quanta
J 0
(-4300 7075);
PAINT MONO (-4300 7075);
DISPLAY INVISIBLE (-4300 7075);
FORCEPROP 1 LAST PATH I40
J 0
(-4350 7225);
DISPLAY 0.978723 (-4350 7225);
PAINT WHITE (-4350 7225);
DISPLAY INVISIBLE (-4350 7225);
FORCEPROP 2 LAST $SEC 1
J 0
(-4350 7275);
DISPLAY 0.680851 (-4350 7275);
PAINT MONO (-4350 7275);
DISPLAY INVISIBLE (-4350 7275);
FORCEPROP 2 LAST CDS_SEC 1
J 0
(-4350 7275);
DISPLAY 1.021277 (-4350 7275);
DISPLAY INVISIBLE (-4350 7275);
FORCEADD Q_CAP..1
(-4200 7525);
FORCEPROP 1 LAST PART_NUMBER CH6223MEA01
J 0
(-4150 7375);
DISPLAY 0.617021 (-4150 7375);
PAINT BLUE (-4150 7375);
DISPLAY INVISIBLE (-4150 7375);
FORCEPROP 1 LAST TOLERANCE 20%
J 0
(-4150 7525);
DISPLAY 0.617021 (-4150 7525);
PAINT SKYBLUE (-4150 7525);
FORCEPROP 1 LAST PACK_TYPE C0805
J 0
(-4150 7425);
DISPLAY 0.617021 (-4150 7425);
PAINT SKYBLUE (-4150 7425);
FORCEPROP 1 LAST MATERIAL X6S
J 0
(-4150 7475);
DISPLAY 0.617021 (-4150 7475);
PAINT SKYBLUE (-4150 7475);
FORCEPROP 1 LAST VALUE 22UF
J 0
(-4150 7625);
DISPLAY 0.617021 (-4150 7625);
PAINT SKYBLUE (-4150 7625);
FORCEPROP 1 LAST VOLTAGE 16V
J 0
(-4150 7575);
DISPLAY 0.617021 (-4150 7575);
PAINT SKYBLUE (-4150 7575);
FORCEPROP 1 LAST LOCATION PC1199_P1_3
J 0
(-4150 7675);
DISPLAY 0.617021 (-4150 7675);
PAINT AQUA (-4150 7675);
FORCEPROP 1 LASTPIN (-4200 7625) $PN 1
J 0
(-4190 7605);
DISPLAY 0.617021 (-4190 7605);
PAINT MONO (-4190 7605);
FORCEPROP 1 LASTPIN (-4200 7425) $PN 2
J 0
(-4190 7405);
DISPLAY 0.617021 (-4190 7405);
PAINT MONO (-4190 7405);
FORCEPROP 2 LAST CDS_LIB pure_quanta
J 0
(-4200 7525);
DISPLAY INVISIBLE (-4200 7525);
FORCEPROP 1 LAST PATH I41
J 0
(-4150 7675);
DISPLAY 0.978723 (-4150 7675);
PAINT WHITE (-4150 7675);
DISPLAY INVISIBLE (-4150 7675);
FORCEPROP 1 LAST LOCATION PC1199_P1_3
J 0
(-4150 7725);
DISPLAY 1.021277 (-4150 7725);
PAINT AQUA (-4150 7725);
DISPLAY INVISIBLE (-4150 7725);
FORCEPROP 0 LAST $SEC 1
J 0
(-4150 7725);
DISPLAY 0.680851 (-4150 7725);
PAINT MONO (-4150 7725);
DISPLAY INVISIBLE (-4150 7725);
FORCEPROP 0 LAST CDS_SEC 1
J 0
(-4150 7725);
DISPLAY 1.021277 (-4150 7725);
DISPLAY INVISIBLE (-4150 7725);
FORCEADD Q_CAP..1
(-3800 7525);
FORCEPROP 1 LAST PART_NUMBER CH6223MEA01
J 0
(-3750 7375);
DISPLAY 0.617021 (-3750 7375);
PAINT BLUE (-3750 7375);
DISPLAY INVISIBLE (-3750 7375);
FORCEPROP 1 LAST TOLERANCE 20%
J 0
(-3750 7525);
DISPLAY 0.617021 (-3750 7525);
PAINT SKYBLUE (-3750 7525);
FORCEPROP 1 LAST VALUE 22UF
J 0
(-3750 7625);
DISPLAY 0.617021 (-3750 7625);
PAINT SKYBLUE (-3750 7625);
FORCEPROP 1 LAST VOLTAGE 16V
J 0
(-3750 7575);
DISPLAY 0.617021 (-3750 7575);
PAINT SKYBLUE (-3750 7575);
FORCEPROP 1 LAST MATERIAL X6S
J 0
(-3750 7475);
DISPLAY 0.617021 (-3750 7475);
PAINT SKYBLUE (-3750 7475);
FORCEPROP 1 LAST PACK_TYPE C0805
J 0
(-3750 7425);
DISPLAY 0.617021 (-3750 7425);
PAINT SKYBLUE (-3750 7425);
FORCEPROP 1 LAST LOCATION PC1201_P1_3
J 0
(-3750 7675);
DISPLAY 0.617021 (-3750 7675);
PAINT AQUA (-3750 7675);
FORCEPROP 1 LASTPIN (-3800 7625) $PN 1
J 0
(-3790 7605);
DISPLAY 0.617021 (-3790 7605);
PAINT MONO (-3790 7605);
FORCEPROP 1 LASTPIN (-3800 7425) $PN 2
J 0
(-3790 7405);
DISPLAY 0.617021 (-3790 7405);
PAINT MONO (-3790 7405);
FORCEPROP 2 LAST CDS_LIB pure_quanta
J 0
(-3800 7525);
DISPLAY INVISIBLE (-3800 7525);
FORCEPROP 1 LAST PATH I42
J 0
(-3750 7675);
DISPLAY 0.978723 (-3750 7675);
PAINT WHITE (-3750 7675);
DISPLAY INVISIBLE (-3750 7675);
FORCEPROP 1 LAST LOCATION PC1201_P1_3
J 0
(-3750 7725);
DISPLAY 1.021277 (-3750 7725);
PAINT AQUA (-3750 7725);
DISPLAY INVISIBLE (-3750 7725);
FORCEPROP 0 LAST $SEC 1
J 0
(-3750 7725);
DISPLAY 0.680851 (-3750 7725);
PAINT MONO (-3750 7725);
DISPLAY INVISIBLE (-3750 7725);
FORCEPROP 0 LAST CDS_SEC 1
J 0
(-3750 7725);
DISPLAY 1.021277 (-3750 7725);
DISPLAY INVISIBLE (-3750 7725);
FORCEADD Q_RES..1
(-3100 3575);
FORCEPROP 1 LAST PART_NUMBER CS00002JB13
J 0
(-3200 3525);
DISPLAY 0.617021 (-3200 3525);
PAINT BLUE (-3200 3525);
DISPLAY INVISIBLE (-3200 3525);
FORCEPROP 1 LAST MATERIAL CHIP
J 0
(-3250 3475);
DISPLAY 0.617021 (-3250 3475);
PAINT SKYBLUE (-3250 3475);
FORCEPROP 1 LAST PACK_TYPE 0402LF
J 0
(-3100 3475);
DISPLAY 0.617021 (-3100 3475);
PAINT SKYBLUE (-3100 3475);
FORCEPROP 1 LAST WATTAGE 1/16W
J 2
(-2750 3475);
DISPLAY 0.617021 (-2750 3475);
PAINT SKYBLUE (-2750 3475);
FORCEPROP 1 LAST VALUE 0
J 2
(-2950 3575);
DISPLAY 0.617021 (-2950 3575);
PAINT SKYBLUE (-2950 3575);
FORCEPROP 1 LAST TOLERANCE 5%
J 0
(-2925 3575);
DISPLAY 0.617021 (-2925 3575);
PAINT SKYBLUE (-2925 3575);
FORCEPROP 1 LAST LOCATION PR1334
J 0
(-3350 3575);
DISPLAY 0.617021 (-3350 3575);
PAINT AQUA (-3350 3575);
FORCEPROP 1 LASTPIN (-3200 3575) $PN 1
J 0
(-3188 3587);
DISPLAY 0.617021 (-3188 3587);
FORCEPROP 1 LASTPIN (-3000 3575) $PN 2
J 0
(-3038 3587);
DISPLAY 0.617021 (-3038 3587);
FORCEPROP 2 LAST CDS_LIB pure_quanta
J 0
(-3100 3575);
PAINT MONO (-3100 3575);
DISPLAY INVISIBLE (-3100 3575);
FORCEPROP 1 LAST PATH I43
J 0
(-3150 3725);
DISPLAY 0.978723 (-3150 3725);
PAINT WHITE (-3150 3725);
DISPLAY INVISIBLE (-3150 3725);
FORCEPROP 2 LAST $SEC 1
J 0
(-3150 3775);
DISPLAY 0.680851 (-3150 3775);
PAINT MONO (-3150 3775);
DISPLAY INVISIBLE (-3150 3775);
FORCEPROP 2 LAST CDS_SEC 1
J 0
(-3150 3775);
DISPLAY 1.021277 (-3150 3775);
DISPLAY INVISIBLE (-3150 3775);
FORCEADD Q_INDUCTOR..1
(-3100 3850);
FORCEPROP 1 LAST PART_NUMBER CV+13^0KZ11
J 0
(-3225 3960);
DISPLAY 0.617021 (-3225 3960);
PAINT BLUE (-3225 3960);
DISPLAY INVISIBLE (-3225 3960);
FORCEPROP 2 LAST PACK_TYPE SMLF
J 0
(-3225 4050);
DISPLAY 0.617021 (-3225 4050);
PAINT SKYBLUE (-3225 4050);
FORCEPROP 2 LAST VALUE 130NH/106A
J 0
(-3225 4100);
DISPLAY 0.617021 (-3225 4100);
PAINT SKYBLUE (-3225 4100);
FORCEPROP 1 LAST MATERIAL IND
J 0
(-3225 3905);
DISPLAY 0.617021 (-3225 3905);
PAINT SKYBLUE (-3225 3905);
FORCEPROP 1 LAST LOCATION PL113
J 0
(-3225 4010);
DISPLAY 0.617021 (-3225 4010);
PAINT AQUA (-3225 4010);
FORCEPROP 0 LASTPIN (-3200 3825) $PN 1
J 2
(-3210 3835);
DISPLAY 0.617021 (-3210 3835);
PAINT MONO (-3210 3835);
FORCEPROP 0 LASTPIN (-3000 3825) $PN 2
J 0
(-2990 3835);
DISPLAY 0.617021 (-2990 3835);
PAINT MONO (-2990 3835);
FORCEPROP 1 LAST NEEDS_NO_SIZE TRUE
J 0
(-3100 3850);
DISPLAY 0.468085 (-3100 3850);
PAINT GREEN (-3100 3850);
DISPLAY INVISIBLE (-3100 3850);
FORCEPROP 2 LAST CDS_LIB pure_quanta
J 0
(-3100 3850);
DISPLAY INVISIBLE (-3100 3850);
FORCEPROP 1 LAST PATH I44
J 0
(-3025 3905);
DISPLAY 0.723404 (-3025 3905);
PAINT GREEN (-3025 3905);
DISPLAY INVISIBLE (-3025 3905);
FORCEPROP 0 LAST $SEC 1
J 0
(-3225 4150);
DISPLAY 0.680851 (-3225 4150);
PAINT MONO (-3225 4150);
DISPLAY INVISIBLE (-3225 4150);
FORCEPROP 0 LAST CDS_SEC 1
J 0
(-3225 4150);
DISPLAY 1.021277 (-3225 4150);
DISPLAY INVISIBLE (-3225 4150);
FORCEADD Q_CAP..1
R 2
(-3375 4100);
FORCEPROP 1 LAST PART_NUMBER CH4106K1B01
J 2
(-3425 4050);
DISPLAY 0.617021 (-3425 4050);
PAINT BLUE (-3425 4050);
DISPLAY INVISIBLE (-3425 4050);
FORCEPROP 1 LAST TOLERANCE 10%
J 2
(-3425 4100);
DISPLAY 0.617021 (-3425 4100);
PAINT SKYBLUE (-3425 4100);
FORCEPROP 1 LAST VALUE 100NF
J 2
(-3425 4150);
DISPLAY 0.617021 (-3425 4150);
PAINT SKYBLUE (-3425 4150);
FORCEPROP 1 LAST VOLTAGE 50V
J 2
(-3425 4125);
DISPLAY 0.617021 (-3425 4125);
PAINT SKYBLUE (-3425 4125);
FORCEPROP 1 LAST PACK_TYPE C0402
J 2
(-3425 4025);
DISPLAY 0.617021 (-3425 4025);
PAINT SKYBLUE (-3425 4025);
FORCEPROP 1 LAST MATERIAL X7R
J 2
(-3425 4075);
DISPLAY 0.617021 (-3425 4075);
PAINT SKYBLUE (-3425 4075);
FORCEPROP 1 LAST LOCATION PC1198
J 2
(-3425 4175);
DISPLAY 0.617021 (-3425 4175);
PAINT AQUA (-3425 4175);
FORCEPROP 1 LASTPIN (-3375 4200) $PN 1
J 2
(-3385 4180);
DISPLAY 0.617021 (-3385 4180);
FORCEPROP 1 LASTPIN (-3375 4000) $PN 2
J 2
(-3385 3980);
DISPLAY 0.617021 (-3385 3980);
FORCEPROP 2 LAST CDS_LIB pure_quanta
J 2
(-3375 4100);
PAINT MONO (-3375 4100);
DISPLAY INVISIBLE (-3375 4100);
FORCEPROP 1 LAST PATH I45
J 2
(-3425 4250);
DISPLAY 0.978723 (-3425 4250);
PAINT WHITE (-3425 4250);
DISPLAY INVISIBLE (-3425 4250);
FORCEPROP 2 LAST $SEC 1
J 0
(-3425 4300);
DISPLAY 0.680851 (-3425 4300);
PAINT MONO (-3425 4300);
DISPLAY INVISIBLE (-3425 4300);
FORCEPROP 2 LAST CDS_SEC 1
J 0
(-3425 4300);
DISPLAY 1.021277 (-3425 4300);
DISPLAY INVISIBLE (-3425 4300);
FORCEADD UNIVERSAL_GND..1
(-3200 4350);
FORCEPROP 3 LASTPIN (-3200 4400) SIG_NAME GND\g
J 0
(-3190 4410);
DISPLAY 0.659574 (-3190 4410);
PAINT MONO (-3190 4410);
DISPLAY INVISIBLE (-3190 4410);
FORCEPROP 1 LAST HDL_POWER GND
J 1
(-3175 4275);
DISPLAY 0.872340 (-3175 4275);
PAINT GREEN (-3175 4275);
DISPLAY INVISIBLE (-3175 4275);
FORCEPROP 2 LAST CDS_LIB logical_power
J 0
(-3200 4350);
PAINT MONO (-3200 4350);
DISPLAY INVISIBLE (-3200 4350);
FORCEPROP 1 LAST PATH I46
J 0
(-3125 4350);
DISPLAY 0.872340 (-3125 4350);
PAINT AQUA (-3125 4350);
DISPLAY INVISIBLE (-3125 4350);
FORCEADD Q_CAP..1
(-2150 3625);
FORCEPROP 1 LAST PART_NUMBER CH4106K1B01
J 0
(-2100 3450);
DISPLAY 0.617021 (-2100 3450);
PAINT BLUE (-2100 3450);
DISPLAY INVISIBLE (-2100 3450);
FORCEPROP 1 LAST MATERIAL X7R
J 0
(-2100 3550);
DISPLAY 0.617021 (-2100 3550);
PAINT SKYBLUE (-2100 3550);
FORCEPROP 1 LAST PACK_TYPE C0402
J 0
(-2100 3500);
DISPLAY 0.617021 (-2100 3500);
PAINT SKYBLUE (-2100 3500);
FORCEPROP 1 LAST TOLERANCE 10%
J 0
(-2100 3600);
DISPLAY 0.617021 (-2100 3600);
PAINT SKYBLUE (-2100 3600);
FORCEPROP 1 LAST VOLTAGE 50V
J 0
(-2100 3650);
DISPLAY 0.617021 (-2100 3650);
PAINT SKYBLUE (-2100 3650);
FORCEPROP 1 LAST VALUE 100NF
J 0
(-2100 3700);
DISPLAY 0.617021 (-2100 3700);
PAINT SKYBLUE (-2100 3700);
FORCEPROP 1 LAST LOCATION PC1203_P1_4
J 0
(-2100 3750);
DISPLAY 0.617021 (-2100 3750);
PAINT AQUA (-2100 3750);
FORCEPROP 1 LASTPIN (-2150 3725) $PN 1
J 0
(-2140 3705);
DISPLAY 0.617021 (-2140 3705);
PAINT MONO (-2140 3705);
FORCEPROP 1 LASTPIN (-2150 3525) $PN 2
J 0
(-2140 3505);
DISPLAY 0.617021 (-2140 3505);
PAINT MONO (-2140 3505);
FORCEPROP 2 LAST CDS_LIB pure_quanta
J 0
(-2150 3625);
DISPLAY INVISIBLE (-2150 3625);
FORCEPROP 1 LAST PATH I47
J 0
(-2100 3775);
DISPLAY 0.978723 (-2100 3775);
PAINT WHITE (-2100 3775);
DISPLAY INVISIBLE (-2100 3775);
FORCEPROP 1 LAST LOCATION PC1203_P1_4
J 0
(-2100 3800);
DISPLAY 1.021277 (-2100 3800);
PAINT AQUA (-2100 3800);
DISPLAY INVISIBLE (-2100 3800);
FORCEPROP 0 LAST $SEC 1
J 0
(-2100 3800);
DISPLAY 0.680851 (-2100 3800);
PAINT MONO (-2100 3800);
DISPLAY INVISIBLE (-2100 3800);
FORCEPROP 0 LAST CDS_SEC 1
J 0
(-2100 3800);
DISPLAY 1.021277 (-2100 3800);
DISPLAY INVISIBLE (-2100 3800);
FORCEADD Q_CAP..1
(-1625 3625);
FORCEPROP 1 LAST PART_NUMBER CH622KMEA03
J 0
(-1575 3450);
DISPLAY 0.617021 (-1575 3450);
PAINT BLUE (-1575 3450);
DISPLAY INVISIBLE (-1575 3450);
FORCEPROP 1 LAST TOLERANCE 20%
J 0
(-1575 3600);
DISPLAY 0.617021 (-1575 3600);
PAINT SKYBLUE (-1575 3600);
FORCEPROP 1 LAST PACK_TYPE C0805
J 0
(-1575 3500);
DISPLAY 0.617021 (-1575 3500);
PAINT SKYBLUE (-1575 3500);
FORCEPROP 1 LAST VOLTAGE 4V
J 0
(-1575 3650);
DISPLAY 0.617021 (-1575 3650);
PAINT SKYBLUE (-1575 3650);
FORCEPROP 1 LAST MATERIAL X6S
J 0
(-1575 3550);
DISPLAY 0.617021 (-1575 3550);
PAINT SKYBLUE (-1575 3550);
FORCEPROP 1 LAST VALUE 22UF
J 0
(-1575 3700);
DISPLAY 0.617021 (-1575 3700);
PAINT SKYBLUE (-1575 3700);
FORCEPROP 1 LAST LOCATION PC1207_P1_4
J 0
(-1575 3750);
DISPLAY 0.617021 (-1575 3750);
PAINT AQUA (-1575 3750);
FORCEPROP 1 LASTPIN (-1625 3725) $PN 1
J 0
(-1615 3705);
DISPLAY 0.617021 (-1615 3705);
PAINT MONO (-1615 3705);
FORCEPROP 1 LASTPIN (-1625 3525) $PN 2
J 0
(-1615 3505);
DISPLAY 0.617021 (-1615 3505);
PAINT MONO (-1615 3505);
FORCEPROP 2 LAST CDS_LIB pure_quanta
J 0
(-1625 3625);
DISPLAY INVISIBLE (-1625 3625);
FORCEPROP 1 LAST PATH I48
J 0
(-1575 3775);
DISPLAY 0.978723 (-1575 3775);
PAINT WHITE (-1575 3775);
DISPLAY INVISIBLE (-1575 3775);
FORCEPROP 1 LAST LOCATION PC1207_P1_4
J 0
(-1575 3800);
DISPLAY 1.021277 (-1575 3800);
PAINT AQUA (-1575 3800);
DISPLAY INVISIBLE (-1575 3800);
FORCEPROP 0 LAST $SEC 1
J 0
(-1575 3800);
DISPLAY 0.680851 (-1575 3800);
PAINT MONO (-1575 3800);
DISPLAY INVISIBLE (-1575 3800);
FORCEPROP 0 LAST CDS_SEC 1
J 0
(-1575 3800);
DISPLAY 1.021277 (-1575 3800);
DISPLAY INVISIBLE (-1575 3800);
FORCEADD UNIVERSAL_GND..1
(-900 3250);
FORCEPROP 3 LASTPIN (-900 3300) SIG_NAME GND\g
J 0
(-890 3310);
DISPLAY 0.659574 (-890 3310);
PAINT MONO (-890 3310);
DISPLAY INVISIBLE (-890 3310);
FORCEPROP 1 LAST HDL_POWER GND
J 1
(-875 3175);
DISPLAY 0.872340 (-875 3175);
PAINT GREEN (-875 3175);
DISPLAY INVISIBLE (-875 3175);
FORCEPROP 2 LAST CDS_LIB logical_power
J 0
(-900 3250);
PAINT MONO (-900 3250);
DISPLAY INVISIBLE (-900 3250);
FORCEPROP 1 LAST PATH I49
J 0
(-825 3250);
DISPLAY 0.872340 (-825 3250);
PAINT AQUA (-825 3250);
DISPLAY INVISIBLE (-825 3250);
FORCEADD Q_RES..2
R 2
(-7800 6125);
FORCEPROP 1 LAST PART_NUMBER CS28872FB01
J 2
(-7850 6000);
DISPLAY 0.617021 (-7850 6000);
PAINT BLUE (-7850 6000);
DISPLAY INVISIBLE (-7850 6000);
FORCEPROP 1 LAST PACK_TYPE 0402LF
J 2
(-7850 5950);
DISPLAY 0.617021 (-7850 5950);
PAINT SKYBLUE (-7850 5950);
FORCEPROP 1 LAST VALUE 8.87K
J 2
(-7855 6200);
DISPLAY 0.617021 (-7855 6200);
PAINT SKYBLUE (-7855 6200);
FORCEPROP 1 LAST TOLERANCE 1%
J 2
(-7855 6150);
DISPLAY 0.617021 (-7855 6150);
PAINT SKYBLUE (-7855 6150);
FORCEPROP 1 LAST WATTAGE 1/16W
J 2
(-7850 6100);
DISPLAY 0.617021 (-7850 6100);
PAINT SKYBLUE (-7850 6100);
FORCEPROP 1 LAST MATERIAL EMPTY
J 2
(-7850 6050);
DISPLAY 0.617021 (-7850 6050);
PAINT RED (-7850 6050);
FORCEPROP 1 LAST LOCATION PR1305
J 2
(-7845 6250);
DISPLAY 0.617021 (-7845 6250);
PAINT AQUA (-7845 6250);
FORCEPROP 1 LASTPIN (-7800 6225) $PN 1
J 2
(-7805 6187);
DISPLAY 0.617021 (-7805 6187);
PAINT MONO (-7805 6187);
FORCEPROP 1 LASTPIN (-7800 6025) $PN 2
J 2
(-7805 6035);
DISPLAY 0.617021 (-7805 6035);
PAINT MONO (-7805 6035);
FORCEPROP 2 LAST CDS_LIB pure_quanta
J 2
(-7800 6125);
DISPLAY INVISIBLE (-7800 6125);
FORCEPROP 1 LAST PATH I5
J 2
(-7850 6300);
DISPLAY 0.978723 (-7850 6300);
PAINT WHITE (-7850 6300);
DISPLAY INVISIBLE (-7850 6300);
FORCEPROP 1 LAST LOCATION PR1305
J 2
(-7850 6300);
DISPLAY 1.021277 (-7850 6300);
PAINT AQUA (-7850 6300);
DISPLAY INVISIBLE (-7850 6300);
FORCEPROP 0 LAST $SEC 1
J 2
(-7850 6300);
DISPLAY 0.680851 (-7850 6300);
PAINT MONO (-7850 6300);
DISPLAY INVISIBLE (-7850 6300);
FORCEPROP 0 LAST CDS_SEC 1
J 2
(-7850 6300);
DISPLAY 1.021277 (-7850 6300);
DISPLAY INVISIBLE (-7850 6300);
FORCEADD Q_CAP..1
(-1200 3625);
FORCEPROP 1 LAST PART_NUMBER CH622KMEA03
J 0
(-1150 3450);
DISPLAY 0.617021 (-1150 3450);
PAINT BLUE (-1150 3450);
DISPLAY INVISIBLE (-1150 3450);
FORCEPROP 1 LAST TOLERANCE 20%
J 0
(-1150 3600);
DISPLAY 0.617021 (-1150 3600);
PAINT SKYBLUE (-1150 3600);
FORCEPROP 1 LAST PACK_TYPE C0805
J 0
(-1150 3500);
DISPLAY 0.617021 (-1150 3500);
PAINT SKYBLUE (-1150 3500);
FORCEPROP 1 LAST VOLTAGE 4V
J 0
(-1150 3650);
DISPLAY 0.617021 (-1150 3650);
PAINT SKYBLUE (-1150 3650);
FORCEPROP 1 LAST MATERIAL X6S
J 0
(-1150 3550);
DISPLAY 0.617021 (-1150 3550);
PAINT SKYBLUE (-1150 3550);
FORCEPROP 1 LAST VALUE 22UF
J 0
(-1150 3700);
DISPLAY 0.617021 (-1150 3700);
PAINT SKYBLUE (-1150 3700);
FORCEPROP 1 LAST LOCATION PC1209_P1_4
J 0
(-1150 3750);
DISPLAY 0.617021 (-1150 3750);
PAINT AQUA (-1150 3750);
FORCEPROP 1 LASTPIN (-1200 3725) $PN 1
J 0
(-1190 3705);
DISPLAY 0.617021 (-1190 3705);
PAINT MONO (-1190 3705);
FORCEPROP 1 LASTPIN (-1200 3525) $PN 2
J 0
(-1190 3505);
DISPLAY 0.617021 (-1190 3505);
PAINT MONO (-1190 3505);
FORCEPROP 2 LAST CDS_LIB pure_quanta
J 0
(-1200 3625);
DISPLAY INVISIBLE (-1200 3625);
FORCEPROP 1 LAST PATH I50
J 0
(-1150 3775);
DISPLAY 0.978723 (-1150 3775);
PAINT WHITE (-1150 3775);
DISPLAY INVISIBLE (-1150 3775);
FORCEPROP 1 LAST LOCATION PC1209_P1_4
J 0
(-1150 3800);
DISPLAY 1.021277 (-1150 3800);
PAINT AQUA (-1150 3800);
DISPLAY INVISIBLE (-1150 3800);
FORCEPROP 0 LAST $SEC 1
J 0
(-1150 3800);
DISPLAY 0.680851 (-1150 3800);
PAINT MONO (-1150 3800);
DISPLAY INVISIBLE (-1150 3800);
FORCEPROP 0 LAST CDS_SEC 1
J 0
(-1150 3800);
DISPLAY 1.021277 (-1150 3800);
DISPLAY INVISIBLE (-1150 3800);
FORCEADD VCC15..1
(-900 4025);
FORCEPROP 3 LASTPIN (-900 3975) SIG_NAME PVCCFA_EHV_FIVRA_CPU1\g
J 0
(-890 3985);
DISPLAY 0.659574 (-890 3985);
PAINT MONO (-890 3985);
DISPLAY INVISIBLE (-890 3985);
FORCEPROP 1 LAST HDL_POWER PVCCFA_EHV_FIVRA_CPU1
J 1
(-900 4075);
DISPLAY 0.617021 (-900 4075);
PAINT GREEN (-900 4075);
FORCEPROP 2 LAST CDS_LIB logical_power
J 0
(-900 4025);
DISPLAY INVISIBLE (-900 4025);
FORCEPROP 1 LAST PATH I51
J 0
(-850 4050);
DISPLAY 0.872340 (-850 4050);
PAINT AQUA (-850 4050);
DISPLAY INVISIBLE (-850 4050);
FORCEADD Q_CAP..1
(-3350 4725);
FORCEPROP 1 LAST PART_NUMBER CH6223MEA01
J 0
(-3300 4575);
DISPLAY 0.617021 (-3300 4575);
PAINT BLUE (-3300 4575);
DISPLAY INVISIBLE (-3300 4575);
FORCEPROP 1 LAST TOLERANCE 20%
J 0
(-3300 4725);
DISPLAY 0.617021 (-3300 4725);
PAINT SKYBLUE (-3300 4725);
FORCEPROP 1 LAST MATERIAL X6S
J 0
(-3300 4675);
DISPLAY 0.617021 (-3300 4675);
PAINT SKYBLUE (-3300 4675);
FORCEPROP 1 LAST PACK_TYPE C0805
J 0
(-3300 4625);
DISPLAY 0.617021 (-3300 4625);
PAINT SKYBLUE (-3300 4625);
FORCEPROP 1 LAST VOLTAGE 16V
J 0
(-3300 4775);
DISPLAY 0.617021 (-3300 4775);
PAINT SKYBLUE (-3300 4775);
FORCEPROP 1 LAST VALUE 22UF
J 0
(-3300 4825);
DISPLAY 0.617021 (-3300 4825);
PAINT SKYBLUE (-3300 4825);
FORCEPROP 1 LAST LOCATION PC727_P1_4
J 0
(-3300 4875);
DISPLAY 0.617021 (-3300 4875);
PAINT AQUA (-3300 4875);
FORCEPROP 1 LASTPIN (-3350 4825) $PN 1
J 0
(-3340 4805);
DISPLAY 0.787234 (-3340 4805);
PAINT MONO (-3340 4805);
FORCEPROP 1 LASTPIN (-3350 4625) $PN 2
J 0
(-3340 4605);
DISPLAY 0.787234 (-3340 4605);
PAINT MONO (-3340 4605);
FORCEPROP 2 LAST CDS_LIB pure_quanta
J 0
(-3350 4725);
DISPLAY INVISIBLE (-3350 4725);
FORCEPROP 1 LAST PATH I52
J 0
(-3300 4875);
DISPLAY 0.978723 (-3300 4875);
PAINT WHITE (-3300 4875);
DISPLAY INVISIBLE (-3300 4875);
FORCEPROP 0 LAST $SEC 1
J 0
(-3300 4875);
DISPLAY 0.680851 (-3300 4875);
PAINT MONO (-3300 4875);
DISPLAY INVISIBLE (-3300 4875);
FORCEPROP 0 LAST CDS_SEC 1
J 0
(-3300 4875);
DISPLAY 1.021277 (-3300 4875);
DISPLAY INVISIBLE (-3300 4875);
FORCEADD VCC15..1
(-3200 5100);
FORCEPROP 3 LASTPIN (-3200 5050) SIG_NAME SW_P12V_PVCCFA_EHV_FIVRA_CPU1_L\g
J 0
(-3190 5060);
DISPLAY 0.659574 (-3190 5060);
PAINT MONO (-3190 5060);
DISPLAY INVISIBLE (-3190 5060);
FORCEPROP 1 LAST HDL_POWER SW_P12V_PVCCFA_EHV_FIVRA_CPU1_L
J 1
(-3150 5150);
DISPLAY 0.617021 (-3150 5150);
PAINT GREEN (-3150 5150);
FORCEPROP 2 LAST CDS_LIB logical_power
J 0
(-3200 5100);
DISPLAY INVISIBLE (-3200 5100);
FORCEPROP 1 LAST PATH I53
J 0
(-3150 5125);
DISPLAY 0.872340 (-3150 5125);
PAINT AQUA (-3150 5125);
DISPLAY INVISIBLE (-3150 5125);
FORCEADD Q_RES..1
(-3100 6375);
FORCEPROP 1 LAST PART_NUMBER CS00002JB13
J 0
(-3200 6325);
DISPLAY 0.617021 (-3200 6325);
PAINT BLUE (-3200 6325);
DISPLAY INVISIBLE (-3200 6325);
FORCEPROP 1 LAST MATERIAL CHIP
J 0
(-3200 6275);
DISPLAY 0.617021 (-3200 6275);
PAINT SKYBLUE (-3200 6275);
FORCEPROP 1 LAST TOLERANCE 5%
J 0
(-2925 6375);
DISPLAY 0.617021 (-2925 6375);
PAINT SKYBLUE (-2925 6375);
FORCEPROP 1 LAST VALUE 0
J 2
(-2950 6375);
DISPLAY 0.617021 (-2950 6375);
PAINT SKYBLUE (-2950 6375);
FORCEPROP 1 LAST WATTAGE 1/16W
J 2
(-2875 6275);
DISPLAY 0.617021 (-2875 6275);
PAINT SKYBLUE (-2875 6275);
FORCEPROP 1 LAST PACK_TYPE 0402LF
J 0
(-3100 6275);
DISPLAY 0.617021 (-3100 6275);
PAINT SKYBLUE (-3100 6275);
FORCEPROP 1 LAST LOCATION PR1333
J 0
(-3350 6375);
DISPLAY 0.617021 (-3350 6375);
PAINT AQUA (-3350 6375);
FORCEPROP 1 LASTPIN (-3200 6375) $PN 1
J 0
(-3188 6387);
DISPLAY 0.617021 (-3188 6387);
FORCEPROP 1 LASTPIN (-3000 6375) $PN 2
J 0
(-3038 6387);
DISPLAY 0.617021 (-3038 6387);
FORCEPROP 2 LAST CDS_LIB pure_quanta
J 0
(-3100 6375);
PAINT MONO (-3100 6375);
DISPLAY INVISIBLE (-3100 6375);
FORCEPROP 1 LAST PATH I54
J 0
(-3150 6525);
DISPLAY 0.978723 (-3150 6525);
PAINT WHITE (-3150 6525);
DISPLAY INVISIBLE (-3150 6525);
FORCEPROP 2 LAST $SEC 1
J 0
(-3150 6575);
DISPLAY 0.680851 (-3150 6575);
PAINT MONO (-3150 6575);
DISPLAY INVISIBLE (-3150 6575);
FORCEPROP 2 LAST CDS_SEC 1
J 0
(-3150 6575);
DISPLAY 1.021277 (-3150 6575);
DISPLAY INVISIBLE (-3150 6575);
FORCEADD Q_CAPP..1
(-1625 5175);
FORCEPROP 1 LAST PART_NUMBER CC7560JMD16
J 0
(-1550 5025);
DISPLAY 0.617021 (-1550 5025);
PAINT BLUE (-1550 5025);
DISPLAY INVISIBLE (-1550 5025);
FORCEPROP 1 LAST PACK_TYPE THLF
J 0
(-1550 5075);
DISPLAY 0.617021 (-1550 5075);
PAINT SKYBLUE (-1550 5075);
FORCEPROP 1 LAST VALUE 560UF
J 0
(-1550 5275);
DISPLAY 0.617021 (-1550 5275);
PAINT SKYBLUE (-1550 5275);
FORCEPROP 1 LAST TOLERANCE 20%
J 0
(-1550 5225);
DISPLAY 0.617021 (-1550 5225);
PAINT SKYBLUE (-1550 5225);
FORCEPROP 1 LAST MATERIAL OSCON
J 0
(-1550 5125);
DISPLAY 0.617021 (-1550 5125);
PAINT SKYBLUE (-1550 5125);
FORCEPROP 1 LAST VOLTAGE 2.5V
J 0
(-1550 5175);
DISPLAY 0.617021 (-1550 5175);
PAINT SKYBLUE (-1550 5175);
FORCEPROP 1 LAST LOCATION PC1201
J 0
(-1550 5325);
DISPLAY 0.617021 (-1550 5325);
PAINT AQUA (-1550 5325);
FORCEPROP 1 LASTPIN (-1625 5275) $PN 1
J 0
(-1615 5260);
DISPLAY 0.617021 (-1615 5260);
PAINT MONO (-1615 5260);
FORCEPROP 1 LASTPIN (-1625 5075) $PN 2
J 0
(-1615 5060);
DISPLAY 0.617021 (-1615 5060);
PAINT MONO (-1615 5060);
FORCEPROP 2 LAST CDS_LIB pure_quanta
J 0
(-1625 5175);
DISPLAY INVISIBLE (-1625 5175);
FORCEPROP 1 LAST PATH I55
J 0
(-1575 5325);
DISPLAY 0.978723 (-1575 5325);
DISPLAY INVISIBLE (-1575 5325);
FORCEPROP 2 LAST $SEC 1
J 0
(-1575 5375);
DISPLAY 0.680851 (-1575 5375);
PAINT MONO (-1575 5375);
DISPLAY INVISIBLE (-1575 5375);
FORCEPROP 2 LAST CDS_SEC 1
J 0
(-1575 5375);
DISPLAY 1.021277 (-1575 5375);
DISPLAY INVISIBLE (-1575 5375);
FORCEADD Q_CAP..1
(-2050 6425);
FORCEPROP 1 LAST PART_NUMBER CH5103KEB01
J 0
(-2000 6250);
DISPLAY 0.617021 (-2000 6250);
PAINT BLUE (-2000 6250);
DISPLAY INVISIBLE (-2000 6250);
FORCEPROP 1 LAST PACK_TYPE C0402
J 0
(-2000 6300);
DISPLAY 0.617021 (-2000 6300);
PAINT SKYBLUE (-2000 6300);
FORCEPROP 1 LAST VALUE 1UF
J 0
(-2000 6500);
DISPLAY 0.617021 (-2000 6500);
PAINT SKYBLUE (-2000 6500);
FORCEPROP 1 LAST MATERIAL X6S
J 0
(-2000 6350);
DISPLAY 0.617021 (-2000 6350);
PAINT SKYBLUE (-2000 6350);
FORCEPROP 1 LAST TOLERANCE 10%
J 0
(-2000 6400);
DISPLAY 0.617021 (-2000 6400);
PAINT SKYBLUE (-2000 6400);
FORCEPROP 1 LAST VOLTAGE 16V
J 0
(-2000 6450);
DISPLAY 0.617021 (-2000 6450);
PAINT SKYBLUE (-2000 6450);
FORCEPROP 1 LAST LOCATION PC1204_P1_3
J 0
(-2000 6550);
DISPLAY 0.617021 (-2000 6550);
PAINT AQUA (-2000 6550);
FORCEPROP 1 LASTPIN (-2050 6525) $PN 1
J 0
(-2040 6505);
DISPLAY 0.617021 (-2040 6505);
PAINT MONO (-2040 6505);
FORCEPROP 1 LASTPIN (-2050 6325) $PN 2
J 0
(-2040 6305);
DISPLAY 0.617021 (-2040 6305);
PAINT MONO (-2040 6305);
FORCEPROP 2 LAST CDS_LIB pure_quanta
J 0
(-2050 6425);
DISPLAY INVISIBLE (-2050 6425);
FORCEPROP 1 LAST PATH I56
J 0
(-2000 6575);
DISPLAY 0.978723 (-2000 6575);
PAINT WHITE (-2000 6575);
DISPLAY INVISIBLE (-2000 6575);
FORCEPROP 1 LAST LOCATION PC1204_P1_3
J 0
(-2000 6600);
DISPLAY 1.021277 (-2000 6600);
PAINT AQUA (-2000 6600);
DISPLAY INVISIBLE (-2000 6600);
FORCEPROP 0 LAST $SEC 1
J 0
(-2000 6600);
DISPLAY 0.680851 (-2000 6600);
PAINT MONO (-2000 6600);
DISPLAY INVISIBLE (-2000 6600);
FORCEPROP 0 LAST CDS_SEC 1
J 0
(-2000 6600);
DISPLAY 1.021277 (-2000 6600);
DISPLAY INVISIBLE (-2000 6600);
FORCEADD Q_INDUCTOR..1
(-3100 6650);
FORCEPROP 1 LAST PART_NUMBER CV+13^0KZ11
J 0
(-3225 6760);
DISPLAY 0.617021 (-3225 6760);
PAINT BLUE (-3225 6760);
DISPLAY INVISIBLE (-3225 6760);
FORCEPROP 1 LAST MATERIAL IND
J 0
(-3225 6705);
DISPLAY 0.617021 (-3225 6705);
PAINT SKYBLUE (-3225 6705);
FORCEPROP 2 LAST VALUE 130NH/106A
J 0
(-3225 6900);
DISPLAY 0.617021 (-3225 6900);
PAINT SKYBLUE (-3225 6900);
FORCEPROP 2 LAST PACK_TYPE SMLF
J 0
(-3225 6850);
DISPLAY 0.617021 (-3225 6850);
PAINT SKYBLUE (-3225 6850);
FORCEPROP 1 LAST LOCATION PL12
J 0
(-3225 6810);
DISPLAY 0.617021 (-3225 6810);
PAINT AQUA (-3225 6810);
FORCEPROP 0 LASTPIN (-3200 6625) $PN 1
J 2
(-3210 6635);
DISPLAY 0.617021 (-3210 6635);
PAINT MONO (-3210 6635);
FORCEPROP 0 LASTPIN (-3000 6625) $PN 2
J 0
(-2990 6635);
DISPLAY 0.617021 (-2990 6635);
PAINT MONO (-2990 6635);
FORCEPROP 2 LAST CDS_LIB pure_quanta
J 0
(-3100 6650);
DISPLAY INVISIBLE (-3100 6650);
FORCEPROP 1 LAST NEEDS_NO_SIZE TRUE
J 0
(-3100 6650);
DISPLAY 0.468085 (-3100 6650);
PAINT GREEN (-3100 6650);
DISPLAY INVISIBLE (-3100 6650);
FORCEPROP 1 LAST PATH I57
J 0
(-3025 6705);
DISPLAY 0.723404 (-3025 6705);
PAINT GREEN (-3025 6705);
DISPLAY INVISIBLE (-3025 6705);
FORCEPROP 0 LAST $SEC 1
J 0
(-3225 6950);
DISPLAY 0.680851 (-3225 6950);
PAINT MONO (-3225 6950);
DISPLAY INVISIBLE (-3225 6950);
FORCEPROP 0 LAST CDS_SEC 1
J 0
(-3225 6950);
DISPLAY 1.021277 (-3225 6950);
DISPLAY INVISIBLE (-3225 6950);
FORCEADD Q_CAP..1
R 2
(-3375 6900);
FORCEPROP 1 LAST PART_NUMBER CH4106K1B01
J 2
(-3425 6850);
DISPLAY 0.617021 (-3425 6850);
PAINT BLUE (-3425 6850);
DISPLAY INVISIBLE (-3425 6850);
FORCEPROP 1 LAST MATERIAL X7R
J 2
(-3425 6875);
DISPLAY 0.617021 (-3425 6875);
PAINT SKYBLUE (-3425 6875);
FORCEPROP 1 LAST VALUE 100NF
J 2
(-3425 6950);
DISPLAY 0.617021 (-3425 6950);
PAINT SKYBLUE (-3425 6950);
FORCEPROP 1 LAST VOLTAGE 50V
J 2
(-3425 6925);
DISPLAY 0.617021 (-3425 6925);
PAINT SKYBLUE (-3425 6925);
FORCEPROP 1 LAST TOLERANCE 10%
J 2
(-3425 6900);
DISPLAY 0.617021 (-3425 6900);
PAINT SKYBLUE (-3425 6900);
FORCEPROP 1 LAST PACK_TYPE C0402
J 2
(-3425 6825);
DISPLAY 0.617021 (-3425 6825);
PAINT SKYBLUE (-3425 6825);
FORCEPROP 1 LAST LOCATION PC1197
J 2
(-3425 6975);
DISPLAY 0.617021 (-3425 6975);
PAINT AQUA (-3425 6975);
FORCEPROP 1 LASTPIN (-3375 7000) $PN 1
J 2
(-3385 6980);
DISPLAY 0.617021 (-3385 6980);
FORCEPROP 1 LASTPIN (-3375 6800) $PN 2
J 2
(-3385 6780);
DISPLAY 0.617021 (-3385 6780);
FORCEPROP 2 LAST CDS_LIB pure_quanta
J 2
(-3375 6900);
PAINT MONO (-3375 6900);
DISPLAY INVISIBLE (-3375 6900);
FORCEPROP 1 LAST PATH I58
J 2
(-3425 7050);
DISPLAY 0.978723 (-3425 7050);
PAINT WHITE (-3425 7050);
DISPLAY INVISIBLE (-3425 7050);
FORCEPROP 2 LAST $SEC 1
J 0
(-3425 7100);
DISPLAY 0.680851 (-3425 7100);
PAINT MONO (-3425 7100);
DISPLAY INVISIBLE (-3425 7100);
FORCEPROP 2 LAST CDS_SEC 1
J 0
(-3425 7100);
DISPLAY 1.021277 (-3425 7100);
DISPLAY INVISIBLE (-3425 7100);
FORCEADD UNIVERSAL_GND..1
(-3200 7175);
FORCEPROP 3 LASTPIN (-3200 7225) SIG_NAME GND\g
J 0
(-3190 7235);
DISPLAY 0.659574 (-3190 7235);
PAINT MONO (-3190 7235);
DISPLAY INVISIBLE (-3190 7235);
FORCEPROP 1 LAST HDL_POWER GND
J 1
(-3175 7100);
DISPLAY 0.872340 (-3175 7100);
PAINT GREEN (-3175 7100);
DISPLAY INVISIBLE (-3175 7100);
FORCEPROP 2 LAST CDS_LIB logical_power
J 0
(-3200 7175);
PAINT MONO (-3200 7175);
DISPLAY INVISIBLE (-3200 7175);
FORCEPROP 1 LAST PATH I59
J 0
(-3125 7175);
DISPLAY 0.872340 (-3125 7175);
PAINT AQUA (-3125 7175);
DISPLAY INVISIBLE (-3125 7175);
FORCEADD UNIVERSAL_GND..1
(-7875 6325);
FORCEPROP 3 LASTPIN (-7875 6375) SIG_NAME GND\g
J 0
(-7865 6385);
DISPLAY 0.659574 (-7865 6385);
PAINT MONO (-7865 6385);
DISPLAY INVISIBLE (-7865 6385);
FORCEPROP 1 LAST HDL_POWER GND
J 1
(-7850 6250);
DISPLAY 0.872340 (-7850 6250);
PAINT GREEN (-7850 6250);
DISPLAY INVISIBLE (-7850 6250);
FORCEPROP 2 LAST CDS_LIB logical_power
J 0
(-7875 6325);
PAINT MONO (-7875 6325);
DISPLAY INVISIBLE (-7875 6325);
FORCEPROP 1 LAST PATH I6
J 0
(-7800 6325);
DISPLAY 0.872340 (-7800 6325);
PAINT AQUA (-7800 6325);
DISPLAY INVISIBLE (-7800 6325);
FORCEADD Q_CAP..1
(-3350 7525);
FORCEPROP 1 LAST PART_NUMBER CH6223MEA01
J 0
(-3300 7375);
DISPLAY 0.617021 (-3300 7375);
PAINT BLUE (-3300 7375);
DISPLAY INVISIBLE (-3300 7375);
FORCEPROP 1 LAST TOLERANCE 20%
J 0
(-3300 7525);
DISPLAY 0.617021 (-3300 7525);
PAINT SKYBLUE (-3300 7525);
FORCEPROP 1 LAST VOLTAGE 16V
J 0
(-3300 7575);
DISPLAY 0.617021 (-3300 7575);
PAINT SKYBLUE (-3300 7575);
FORCEPROP 1 LAST PACK_TYPE C0805
J 0
(-3300 7425);
DISPLAY 0.617021 (-3300 7425);
PAINT SKYBLUE (-3300 7425);
FORCEPROP 1 LAST VALUE 22UF
J 0
(-3300 7625);
DISPLAY 0.617021 (-3300 7625);
PAINT SKYBLUE (-3300 7625);
FORCEPROP 1 LAST MATERIAL X6S
J 0
(-3300 7475);
DISPLAY 0.617021 (-3300 7475);
PAINT SKYBLUE (-3300 7475);
FORCEPROP 1 LAST LOCATION PC726_P1_3
J 0
(-3300 7675);
DISPLAY 0.617021 (-3300 7675);
PAINT AQUA (-3300 7675);
FORCEPROP 1 LASTPIN (-3350 7625) $PN 1
J 0
(-3340 7605);
DISPLAY 0.787234 (-3340 7605);
PAINT MONO (-3340 7605);
FORCEPROP 1 LASTPIN (-3350 7425) $PN 2
J 0
(-3340 7405);
DISPLAY 0.787234 (-3340 7405);
PAINT MONO (-3340 7405);
FORCEPROP 2 LAST CDS_LIB pure_quanta
J 0
(-3350 7525);
DISPLAY INVISIBLE (-3350 7525);
FORCEPROP 1 LAST PATH I60
J 0
(-3300 7675);
DISPLAY 0.978723 (-3300 7675);
PAINT WHITE (-3300 7675);
DISPLAY INVISIBLE (-3300 7675);
FORCEPROP 0 LAST $SEC 1
J 0
(-3300 7675);
DISPLAY 0.680851 (-3300 7675);
PAINT MONO (-3300 7675);
DISPLAY INVISIBLE (-3300 7675);
FORCEPROP 0 LAST CDS_SEC 1
J 0
(-3300 7675);
DISPLAY 1.021277 (-3300 7675);
DISPLAY INVISIBLE (-3300 7675);
FORCEADD VCC15..1
(-3200 7900);
FORCEPROP 3 LASTPIN (-3200 7850) SIG_NAME SW_P12V_PVCCFA_EHV_FIVRA_CPU1_R\g
J 0
(-3190 7860);
DISPLAY 0.659574 (-3190 7860);
PAINT MONO (-3190 7860);
DISPLAY INVISIBLE (-3190 7860);
FORCEPROP 1 LAST HDL_POWER SW_P12V_PVCCFA_EHV_FIVRA_CPU1_R
J 1
(-3150 7950);
DISPLAY 0.617021 (-3150 7950);
PAINT GREEN (-3150 7950);
FORCEPROP 2 LAST CDS_LIB logical_power
J 0
(-3200 7900);
DISPLAY INVISIBLE (-3200 7900);
FORCEPROP 1 LAST PATH I61
J 0
(-3150 7925);
DISPLAY 0.872340 (-3150 7925);
PAINT AQUA (-3150 7925);
DISPLAY INVISIBLE (-3150 7925);
FORCEADD Q_CAP..1
(-2075 7300);
FORCEPROP 1 LAST PART_NUMBER CH4106K1B01
J 0
(-2025 7150);
DISPLAY 0.787234 (-2025 7150);
DISPLAY INVISIBLE (-2025 7150);
FORCEPROP 1 LAST VOLTAGE 50V
J 0
(-2025 7300);
DISPLAY 0.787234 (-2025 7300);
FORCEPROP 1 LAST VALUE 100NF
J 0
(-2025 7350);
DISPLAY 0.787234 (-2025 7350);
FORCEPROP 1 LAST TOLERANCE 10%
J 0
(-2025 7250);
DISPLAY 0.787234 (-2025 7250);
FORCEPROP 1 LAST MATERIAL X7R
J 0
(-2025 7200);
DISPLAY 0.787234 (-2025 7200);
FORCEPROP 1 LAST PACK_TYPE C0402
J 0
(-2025 7100);
DISPLAY 0.787234 (-2025 7100);
FORCEPROP 1 LAST LOCATION PC1658
J 0
(-2025 7400);
DISPLAY 0.787234 (-2025 7400);
FORCEPROP 1 LASTPIN (-2075 7400) $PN 1
J 0
(-2065 7380);
DISPLAY 0.787234 (-2065 7380);
PAINT MONO (-2065 7380);
FORCEPROP 1 LASTPIN (-2075 7200) $PN 2
J 0
(-2065 7180);
DISPLAY 0.787234 (-2065 7180);
PAINT MONO (-2065 7180);
FORCEPROP 2 LAST CDS_LIB pure_quanta
J 0
(-2075 7300);
DISPLAY INVISIBLE (-2075 7300);
FORCEPROP 1 LAST PATH I62
J 0
(-2025 7450);
DISPLAY 0.978723 (-2025 7450);
PAINT WHITE (-2025 7450);
DISPLAY INVISIBLE (-2025 7450);
FORCEPROP 0 LAST $SEC 1
J 0
(-2025 7450);
DISPLAY 0.680851 (-2025 7450);
PAINT MONO (-2025 7450);
DISPLAY INVISIBLE (-2025 7450);
FORCEPROP 0 LAST CDS_SEC 1
J 0
(-2025 7450);
DISPLAY 1.021277 (-2025 7450);
DISPLAY INVISIBLE (-2025 7450);
FORCEADD GND..1
(-2075 7050);
FORCEPROP 3 LASTPIN (-2075 7100) SIG_NAME GND\g
J 0
(-2065 7110);
DISPLAY 0.659574 (-2065 7110);
PAINT MONO (-2065 7110);
DISPLAY INVISIBLE (-2065 7110);
FORCEPROP 1 LAST HDL_POWER GND
J 0
(-2075 7200);
DISPLAY 0.872340 (-2075 7200);
PAINT GREEN (-2075 7200);
DISPLAY INVISIBLE (-2075 7200);
FORCEPROP 2 LAST CDS_LIB logical_power
J 0
(-2075 7050);
DISPLAY INVISIBLE (-2075 7050);
FORCEPROP 1 LAST SIZE 1B
J 0
(-2000 7000);
DISPLAY 0.872340 (-2000 7000);
PAINT AQUA (-2000 7000);
DISPLAY INVISIBLE (-2000 7000);
FORCEPROP 1 LAST PATH I63
J 0
(-2000 7050);
DISPLAY 0.872340 (-2000 7050);
PAINT AQUA (-2000 7050);
DISPLAY INVISIBLE (-2000 7050);
FORCEADD Q_INDUCTOR..1
(-1650 7525);
FORCEPROP 1 LAST PART_NUMBER CV+10G0MZ04
J 0
(-1750 7275);
DISPLAY 0.617021 (-1750 7275);
PAINT BLUE (-1750 7275);
DISPLAY INVISIBLE (-1750 7275);
FORCEPROP 2 LAST PACK_TYPE SMLF
J 0
(-1750 7375);
DISPLAY 0.617021 (-1750 7375);
PAINT SKYBLUE (-1750 7375);
FORCEPROP 1 LAST MATERIAL IND
J 0
(-1750 7325);
DISPLAY 0.617021 (-1750 7325);
PAINT SKYBLUE (-1750 7325);
FORCEPROP 2 LAST VALUE 100NH/16A
J 0
(-1750 7425);
DISPLAY 0.617021 (-1750 7425);
PAINT SKYBLUE (-1750 7425);
FORCEPROP 1 LAST LOCATION PL14
J 0
(-1925 7510);
DISPLAY 0.617021 (-1925 7510);
PAINT AQUA (-1925 7510);
FORCEPROP 2 LASTPIN (-1750 7500) $PN 1
J 2
(-1760 7510);
DISPLAY 0.617021 (-1760 7510);
FORCEPROP 2 LASTPIN (-1550 7500) $PN 2
J 0
(-1540 7510);
DISPLAY 0.617021 (-1540 7510);
FORCEPROP 1 LAST NEEDS_NO_SIZE TRUE
J 0
(-1650 7525);
DISPLAY 0.468085 (-1650 7525);
PAINT GREEN (-1650 7525);
DISPLAY INVISIBLE (-1650 7525);
FORCEPROP 2 LAST CDS_LIB pure_quanta
J 0
(-1650 7525);
PAINT MONO (-1650 7525);
DISPLAY INVISIBLE (-1650 7525);
FORCEPROP 1 LAST PATH I64
J 0
(-1575 7580);
DISPLAY 0.723404 (-1575 7580);
PAINT GREEN (-1575 7580);
DISPLAY INVISIBLE (-1575 7580);
FORCEPROP 2 LAST $SEC 1
J 0
(-1575 7625);
DISPLAY 0.680851 (-1575 7625);
PAINT MONO (-1575 7625);
DISPLAY INVISIBLE (-1575 7625);
FORCEPROP 2 LAST CDS_SEC 1
J 0
(-1575 7625);
DISPLAY 1.021277 (-1575 7625);
DISPLAY INVISIBLE (-1575 7625);
FORCEADD VCC15..1
(-2075 7675);
FORCEPROP 3 LASTPIN (-2075 7625) SIG_NAME P12V_AUX\g
J 0
(-2065 7635);
DISPLAY 0.659574 (-2065 7635);
PAINT MONO (-2065 7635);
DISPLAY INVISIBLE (-2065 7635);
FORCEPROP 1 LAST HDL_POWER P12V_AUX
J 1
(-2050 7725);
DISPLAY 0.617021 (-2050 7725);
PAINT GREEN (-2050 7725);
FORCEPROP 2 LAST CDS_LIB logical_power
J 0
(-2075 7675);
DISPLAY INVISIBLE (-2075 7675);
FORCEPROP 1 LAST PATH I65
J 0
(-2025 7700);
DISPLAY 0.872340 (-2025 7700);
PAINT AQUA (-2025 7700);
DISPLAY INVISIBLE (-2025 7700);
FORCEADD Q_CAP..1
(-1625 6425);
FORCEPROP 1 LAST PART_NUMBER CH622KMEA03
J 0
(-1575 6250);
DISPLAY 0.617021 (-1575 6250);
PAINT BLUE (-1575 6250);
DISPLAY INVISIBLE (-1575 6250);
FORCEPROP 1 LAST TOLERANCE 20%
J 0
(-1575 6400);
DISPLAY 0.617021 (-1575 6400);
PAINT SKYBLUE (-1575 6400);
FORCEPROP 1 LAST PACK_TYPE C0805
J 0
(-1575 6300);
DISPLAY 0.617021 (-1575 6300);
PAINT SKYBLUE (-1575 6300);
FORCEPROP 1 LAST VALUE 22UF
J 0
(-1575 6500);
DISPLAY 0.617021 (-1575 6500);
PAINT SKYBLUE (-1575 6500);
FORCEPROP 1 LAST MATERIAL X6S
J 0
(-1575 6350);
DISPLAY 0.617021 (-1575 6350);
PAINT SKYBLUE (-1575 6350);
FORCEPROP 1 LAST VOLTAGE 4V
J 0
(-1575 6450);
DISPLAY 0.617021 (-1575 6450);
PAINT SKYBLUE (-1575 6450);
FORCEPROP 1 LAST LOCATION PC1206_P1_3
J 0
(-1575 6550);
DISPLAY 0.617021 (-1575 6550);
PAINT AQUA (-1575 6550);
FORCEPROP 1 LASTPIN (-1625 6525) $PN 1
J 0
(-1615 6505);
DISPLAY 0.617021 (-1615 6505);
PAINT MONO (-1615 6505);
FORCEPROP 1 LASTPIN (-1625 6325) $PN 2
J 0
(-1615 6305);
DISPLAY 0.617021 (-1615 6305);
PAINT MONO (-1615 6305);
FORCEPROP 2 LAST CDS_LIB pure_quanta
J 0
(-1625 6425);
DISPLAY INVISIBLE (-1625 6425);
FORCEPROP 1 LAST PATH I66
J 0
(-1575 6575);
DISPLAY 0.978723 (-1575 6575);
PAINT WHITE (-1575 6575);
DISPLAY INVISIBLE (-1575 6575);
FORCEPROP 1 LAST LOCATION PC1206_P1_3
J 0
(-1575 6600);
DISPLAY 1.021277 (-1575 6600);
PAINT AQUA (-1575 6600);
DISPLAY INVISIBLE (-1575 6600);
FORCEPROP 0 LAST $SEC 1
J 0
(-1575 6600);
DISPLAY 0.680851 (-1575 6600);
PAINT MONO (-1575 6600);
DISPLAY INVISIBLE (-1575 6600);
FORCEPROP 0 LAST CDS_SEC 1
J 0
(-1575 6600);
DISPLAY 1.021277 (-1575 6600);
DISPLAY INVISIBLE (-1575 6600);
FORCEADD Q_CAPP..1
(-1100 5175);
FORCEPROP 1 LAST PART_NUMBER CC7560JMD16
J 0
(-1025 5025);
DISPLAY 0.617021 (-1025 5025);
PAINT BLUE (-1025 5025);
DISPLAY INVISIBLE (-1025 5025);
FORCEPROP 1 LAST PACK_TYPE THLF
J 0
(-1025 5075);
DISPLAY 0.617021 (-1025 5075);
PAINT SKYBLUE (-1025 5075);
FORCEPROP 1 LAST VALUE 560UF
J 0
(-1025 5275);
DISPLAY 0.617021 (-1025 5275);
PAINT SKYBLUE (-1025 5275);
FORCEPROP 1 LAST TOLERANCE 20%
J 0
(-1025 5225);
DISPLAY 0.617021 (-1025 5225);
PAINT SKYBLUE (-1025 5225);
FORCEPROP 1 LAST MATERIAL OSCON
J 0
(-1025 5125);
DISPLAY 0.617021 (-1025 5125);
PAINT SKYBLUE (-1025 5125);
FORCEPROP 1 LAST VOLTAGE 2.5V
J 0
(-1025 5175);
DISPLAY 0.617021 (-1025 5175);
PAINT SKYBLUE (-1025 5175);
FORCEPROP 1 LAST LOCATION PC1203
J 0
(-1025 5325);
DISPLAY 0.617021 (-1025 5325);
PAINT AQUA (-1025 5325);
FORCEPROP 1 LASTPIN (-1100 5275) $PN 1
J 0
(-1090 5260);
DISPLAY 0.617021 (-1090 5260);
PAINT MONO (-1090 5260);
FORCEPROP 1 LASTPIN (-1100 5075) $PN 2
J 0
(-1090 5060);
DISPLAY 0.617021 (-1090 5060);
PAINT MONO (-1090 5060);
FORCEPROP 2 LAST CDS_LIB pure_quanta
J 0
(-1100 5175);
DISPLAY INVISIBLE (-1100 5175);
FORCEPROP 1 LAST PATH I67
J 0
(-1050 5325);
DISPLAY 0.978723 (-1050 5325);
DISPLAY INVISIBLE (-1050 5325);
FORCEPROP 2 LAST $SEC 1
J 0
(-1050 5375);
DISPLAY 0.680851 (-1050 5375);
PAINT MONO (-1050 5375);
DISPLAY INVISIBLE (-1050 5375);
FORCEPROP 2 LAST CDS_SEC 1
J 0
(-1050 5375);
DISPLAY 1.021277 (-1050 5375);
DISPLAY INVISIBLE (-1050 5375);
FORCEADD Q_CAP..1
(-1200 6425);
FORCEPROP 1 LAST PART_NUMBER CH622KMEA03
J 0
(-1150 6250);
DISPLAY 0.617021 (-1150 6250);
PAINT BLUE (-1150 6250);
DISPLAY INVISIBLE (-1150 6250);
FORCEPROP 1 LAST TOLERANCE 20%
J 0
(-1150 6400);
DISPLAY 0.617021 (-1150 6400);
PAINT SKYBLUE (-1150 6400);
FORCEPROP 1 LAST PACK_TYPE C0805
J 0
(-1150 6300);
DISPLAY 0.617021 (-1150 6300);
PAINT SKYBLUE (-1150 6300);
FORCEPROP 1 LAST VALUE 22UF
J 0
(-1150 6500);
DISPLAY 0.617021 (-1150 6500);
PAINT SKYBLUE (-1150 6500);
FORCEPROP 1 LAST VOLTAGE 4V
J 0
(-1150 6450);
DISPLAY 0.617021 (-1150 6450);
PAINT SKYBLUE (-1150 6450);
FORCEPROP 1 LAST MATERIAL X6S
J 0
(-1150 6350);
DISPLAY 0.617021 (-1150 6350);
PAINT SKYBLUE (-1150 6350);
FORCEPROP 1 LAST LOCATION PC1208_P1_3
J 0
(-1150 6550);
DISPLAY 0.617021 (-1150 6550);
PAINT AQUA (-1150 6550);
FORCEPROP 1 LASTPIN (-1200 6525) $PN 1
J 0
(-1190 6505);
DISPLAY 0.617021 (-1190 6505);
PAINT MONO (-1190 6505);
FORCEPROP 1 LASTPIN (-1200 6325) $PN 2
J 0
(-1190 6305);
DISPLAY 0.617021 (-1190 6305);
PAINT MONO (-1190 6305);
FORCEPROP 2 LAST CDS_LIB pure_quanta
J 0
(-1200 6425);
DISPLAY INVISIBLE (-1200 6425);
FORCEPROP 1 LAST PATH I68
J 0
(-1150 6575);
DISPLAY 0.978723 (-1150 6575);
PAINT WHITE (-1150 6575);
DISPLAY INVISIBLE (-1150 6575);
FORCEPROP 1 LAST LOCATION PC1208_P1_3
J 0
(-1150 6600);
DISPLAY 1.021277 (-1150 6600);
PAINT AQUA (-1150 6600);
DISPLAY INVISIBLE (-1150 6600);
FORCEPROP 0 LAST $SEC 1
J 0
(-1150 6600);
DISPLAY 0.680851 (-1150 6600);
PAINT MONO (-1150 6600);
DISPLAY INVISIBLE (-1150 6600);
FORCEPROP 0 LAST CDS_SEC 1
J 0
(-1150 6600);
DISPLAY 1.021277 (-1150 6600);
DISPLAY INVISIBLE (-1150 6600);
FORCEADD UNIVERSAL_GND..1
(-900 6050);
FORCEPROP 3 LASTPIN (-900 6100) SIG_NAME GND\g
J 0
(-890 6110);
DISPLAY 0.659574 (-890 6110);
PAINT MONO (-890 6110);
DISPLAY INVISIBLE (-890 6110);
FORCEPROP 1 LAST HDL_POWER GND
J 1
(-875 5975);
DISPLAY 0.872340 (-875 5975);
PAINT GREEN (-875 5975);
DISPLAY INVISIBLE (-875 5975);
FORCEPROP 2 LAST CDS_LIB logical_power
J 0
(-900 6050);
PAINT MONO (-900 6050);
DISPLAY INVISIBLE (-900 6050);
FORCEPROP 1 LAST PATH I69
J 0
(-825 6050);
DISPLAY 0.872340 (-825 6050);
PAINT AQUA (-825 6050);
DISPLAY INVISIBLE (-825 6050);
FORCEADD OFFPAGE..5
(-7350 3325);
FORCEPROP 2 LAST $XR2 284 
J 0
(-7635 3361);
DISPLAY 0.638298 (-7635 3361);
PAINT MONO (-7635 3361);
FORCEPROP 2 LAST $XR1 290 
J 0
(-7635 3289);
DISPLAY 0.638298 (-7635 3289);
PAINT MONO (-7635 3289);
FORCEPROP 2 LAST $XR0 289 
J 0
(-7635 3325);
DISPLAY 0.638298 (-7635 3325);
PAINT MONO (-7635 3325);
FORCEPROP 1 LAST COMMENT_BODY TRUE
J 0
(-7250 3250);
DISPLAY 0.872340 (-7250 3250);
PAINT GREEN (-7250 3250);
DISPLAY INVISIBLE (-7250 3250);
FORCEPROP 1 LAST OFFPAGE TRUE
J 0
(-7025 3200);
DISPLAY 0.872340 (-7025 3200);
PAINT GREEN (-7025 3200);
DISPLAY INVISIBLE (-7025 3200);
FORCEPROP 2 LAST CDS_LIB standard
J 0
(-7350 3325);
DISPLAY INVISIBLE (-7350 3325);
FORCEPROP 2 LAST PATH I7
J 0
(-7625 3400);
DISPLAY 1.021277 (-7625 3400);
DISPLAY INVISIBLE (-7625 3400);
FORCEADD Q_CAPP..1
(-575 5175);
FORCEPROP 1 LAST PART_NUMBER CC7560JMD16
J 0
(-500 5025);
DISPLAY 0.617021 (-500 5025);
PAINT BLUE (-500 5025);
DISPLAY INVISIBLE (-500 5025);
FORCEPROP 1 LAST PACK_TYPE THLF
J 0
(-500 5075);
DISPLAY 0.617021 (-500 5075);
PAINT SKYBLUE (-500 5075);
FORCEPROP 1 LAST VALUE 560UF
J 0
(-500 5275);
DISPLAY 0.617021 (-500 5275);
PAINT SKYBLUE (-500 5275);
FORCEPROP 1 LAST TOLERANCE 20%
J 0
(-500 5225);
DISPLAY 0.617021 (-500 5225);
PAINT SKYBLUE (-500 5225);
FORCEPROP 1 LAST MATERIAL OSCON
J 0
(-500 5125);
DISPLAY 0.617021 (-500 5125);
PAINT SKYBLUE (-500 5125);
FORCEPROP 1 LAST VOLTAGE 2.5V
J 0
(-500 5175);
DISPLAY 0.617021 (-500 5175);
PAINT SKYBLUE (-500 5175);
FORCEPROP 1 LAST LOCATION PC1204
J 0
(-500 5325);
DISPLAY 0.617021 (-500 5325);
PAINT AQUA (-500 5325);
FORCEPROP 1 LASTPIN (-575 5275) $PN 1
J 0
(-565 5260);
DISPLAY 0.617021 (-565 5260);
PAINT MONO (-565 5260);
FORCEPROP 1 LASTPIN (-575 5075) $PN 2
J 0
(-565 5060);
DISPLAY 0.617021 (-565 5060);
PAINT MONO (-565 5060);
FORCEPROP 2 LAST CDS_LIB pure_quanta
J 0
(-575 5175);
DISPLAY INVISIBLE (-575 5175);
FORCEPROP 1 LAST PATH I70
J 0
(-525 5325);
DISPLAY 0.978723 (-525 5325);
DISPLAY INVISIBLE (-525 5325);
FORCEPROP 2 LAST $SEC 1
J 0
(-525 5375);
DISPLAY 0.680851 (-525 5375);
PAINT MONO (-525 5375);
DISPLAY INVISIBLE (-525 5375);
FORCEPROP 2 LAST CDS_SEC 1
J 0
(-525 5375);
DISPLAY 1.021277 (-525 5375);
DISPLAY INVISIBLE (-525 5375);
FORCEADD UNIVERSAL_GND..1
(375 4825);
FORCEPROP 3 LASTPIN (375 4875) SIG_NAME GND\g
J 0
(385 4885);
DISPLAY 0.659574 (385 4885);
PAINT MONO (385 4885);
DISPLAY INVISIBLE (385 4885);
FORCEPROP 1 LAST HDL_POWER GND
J 1
(400 4750);
DISPLAY 0.872340 (400 4750);
PAINT GREEN (400 4750);
DISPLAY INVISIBLE (400 4750);
FORCEPROP 2 LAST CDS_LIB logical_power
J 0
(375 4825);
PAINT MONO (375 4825);
DISPLAY INVISIBLE (375 4825);
FORCEPROP 1 LAST PATH I71
J 0
(450 4825);
DISPLAY 0.872340 (450 4825);
PAINT AQUA (450 4825);
DISPLAY INVISIBLE (450 4825);
FORCEADD Q_CAPP..1
(-75 5175);
FORCEPROP 1 LAST PART_NUMBER CH733LY8802
J 0
(0 5025);
DISPLAY 0.617021 (0 5025);
PAINT BLUE (0 5025);
DISPLAY INVISIBLE (0 5025);
FORCEPROP 1 LAST VOLTAGE 2.5V
J 0
(0 5175);
DISPLAY 0.617021 (0 5175);
PAINT SKYBLUE (0 5175);
FORCEPROP 1 LAST MATERIAL SPCAP
J 0
(0 5125);
DISPLAY 0.617021 (0 5125);
PAINT SKYBLUE (0 5125);
FORCEPROP 1 LAST TOLERANCE +10/-35%
J 0
(0 5225);
DISPLAY 0.617021 (0 5225);
PAINT SKYBLUE (0 5225);
FORCEPROP 1 LAST VALUE 330UF
J 0
(0 5275);
DISPLAY 0.617021 (0 5275);
PAINT SKYBLUE (0 5275);
FORCEPROP 1 LAST PACK_TYPE SMLF
J 0
(0 5075);
DISPLAY 0.617021 (0 5075);
PAINT SKYBLUE (0 5075);
FORCEPROP 1 LAST LOCATION PC1205
J 0
(0 5325);
DISPLAY 0.617021 (0 5325);
PAINT AQUA (0 5325);
FORCEPROP 1 LASTPIN (-75 5275) $PN 1
J 0
(-65 5260);
DISPLAY 0.617021 (-65 5260);
PAINT MONO (-65 5260);
FORCEPROP 1 LASTPIN (-75 5075) $PN 2
J 0
(-65 5060);
DISPLAY 0.617021 (-65 5060);
PAINT MONO (-65 5060);
FORCEPROP 2 LAST CDS_LIB pure_quanta
J 0
(-75 5175);
DISPLAY INVISIBLE (-75 5175);
FORCEPROP 1 LAST PATH I72
J 0
(-25 5325);
DISPLAY 0.978723 (-25 5325);
DISPLAY INVISIBLE (-25 5325);
FORCEPROP 2 LAST $SEC 1
J 0
(-25 5375);
DISPLAY 0.680851 (-25 5375);
PAINT MONO (-25 5375);
DISPLAY INVISIBLE (-25 5375);
FORCEPROP 2 LAST CDS_SEC 1
J 0
(-25 5375);
DISPLAY 1.021277 (-25 5375);
DISPLAY INVISIBLE (-25 5375);
FORCEADD Q_CAPP..1
(375 5175);
FORCEPROP 1 LAST PART_NUMBER CH733LY8802
J 0
(450 5025);
DISPLAY 0.617021 (450 5025);
PAINT BLUE (450 5025);
DISPLAY INVISIBLE (450 5025);
FORCEPROP 1 LAST VOLTAGE 2.5V
J 0
(450 5175);
DISPLAY 0.617021 (450 5175);
PAINT SKYBLUE (450 5175);
FORCEPROP 1 LAST PACK_TYPE SMLF
J 0
(450 5075);
DISPLAY 0.617021 (450 5075);
PAINT SKYBLUE (450 5075);
FORCEPROP 1 LAST MATERIAL SPCAP
J 0
(450 5125);
DISPLAY 0.617021 (450 5125);
PAINT RED (450 5125);
FORCEPROP 1 LAST VALUE 330UF
J 0
(450 5275);
DISPLAY 0.617021 (450 5275);
PAINT SKYBLUE (450 5275);
FORCEPROP 1 LAST TOLERANCE +10/-35%
J 0
(450 5225);
DISPLAY 0.617021 (450 5225);
PAINT SKYBLUE (450 5225);
FORCEPROP 1 LAST LOCATION PC2171
J 0
(450 5325);
DISPLAY 0.617021 (450 5325);
PAINT AQUA (450 5325);
FORCEPROP 1 LASTPIN (375 5275) $PN 1
J 0
(385 5260);
DISPLAY 0.617021 (385 5260);
PAINT MONO (385 5260);
FORCEPROP 1 LASTPIN (375 5075) $PN 2
J 0
(385 5060);
DISPLAY 0.617021 (385 5060);
PAINT MONO (385 5060);
FORCEPROP 2 LAST CDS_LIB pure_quanta
J 0
(375 5175);
DISPLAY INVISIBLE (375 5175);
FORCEPROP 1 LAST PATH I73
J 0
(425 5325);
DISPLAY 0.978723 (425 5325);
DISPLAY INVISIBLE (425 5325);
FORCEPROP 2 LAST $SEC 1
J 0
(425 5375);
DISPLAY 0.680851 (425 5375);
PAINT MONO (425 5375);
DISPLAY INVISIBLE (425 5375);
FORCEPROP 2 LAST CDS_SEC 1
J 0
(425 5375);
DISPLAY 1.021277 (425 5375);
DISPLAY INVISIBLE (425 5375);
FORCEADD VCC15..1
(375 5500);
FORCEPROP 3 LASTPIN (375 5450) SIG_NAME PVCCFA_EHV_FIVRA_CPU1\g
J 0
(385 5460);
DISPLAY 0.659574 (385 5460);
PAINT MONO (385 5460);
DISPLAY INVISIBLE (385 5460);
FORCEPROP 1 LAST HDL_POWER PVCCFA_EHV_FIVRA_CPU1
J 1
(375 5550);
DISPLAY 0.617021 (375 5550);
PAINT GREEN (375 5550);
FORCEPROP 2 LAST CDS_LIB logical_power
J 0
(375 5500);
DISPLAY INVISIBLE (375 5500);
FORCEPROP 1 LAST PATH I74
J 0
(425 5525);
DISPLAY 0.872340 (425 5525);
PAINT AQUA (425 5525);
DISPLAY INVISIBLE (425 5525);
FORCEADD Q_CAP..1
(-1275 7275);
FORCEPROP 1 LAST PART_NUMBER CH6223MEA01
J 0
(-1225 7150);
DISPLAY 0.404255 (-1225 7150);
DISPLAY INVISIBLE (-1225 7150);
FORCEPROP 1 LAST TOLERANCE 20%
J 0
(-1225 7250);
DISPLAY 0.510638 (-1225 7250);
FORCEPROP 1 LAST MATERIAL X6S
J 0
(-1225 7200);
DISPLAY 0.510638 (-1225 7200);
FORCEPROP 1 LAST VALUE 22UF
J 0
(-1225 7350);
DISPLAY 0.510638 (-1225 7350);
FORCEPROP 1 LAST VOLTAGE 16V
J 0
(-1225 7300);
DISPLAY 0.510638 (-1225 7300);
FORCEPROP 1 LAST PACK_TYPE C0805
J 0
(-1225 7100);
DISPLAY 0.510638 (-1225 7100);
FORCEPROP 1 LAST LOCATION PC1681
J 0
(-1225 7400);
DISPLAY 0.510638 (-1225 7400);
FORCEPROP 1 LASTPIN (-1275 7375) $PN 1
J 0
(-1265 7355);
DISPLAY 0.787234 (-1265 7355);
PAINT MONO (-1265 7355);
FORCEPROP 1 LASTPIN (-1275 7175) $PN 2
J 0
(-1265 7155);
DISPLAY 0.787234 (-1265 7155);
PAINT MONO (-1265 7155);
FORCEPROP 2 LAST CDS_LIB pure_quanta
J 0
(-1275 7275);
DISPLAY INVISIBLE (-1275 7275);
FORCEPROP 1 LAST PATH I75
J 0
(-1225 7425);
DISPLAY 0.978723 (-1225 7425);
PAINT WHITE (-1225 7425);
DISPLAY INVISIBLE (-1225 7425);
FORCEPROP 0 LAST $SEC 1
J 0
(-1225 7425);
DISPLAY 0.680851 (-1225 7425);
PAINT MONO (-1225 7425);
DISPLAY INVISIBLE (-1225 7425);
FORCEPROP 0 LAST CDS_SEC 1
J 0
(-1225 7425);
DISPLAY 1.021277 (-1225 7425);
DISPLAY INVISIBLE (-1225 7425);
FORCEADD VCC15..1
(-900 6825);
FORCEPROP 3 LASTPIN (-900 6775) SIG_NAME PVCCFA_EHV_FIVRA_CPU1\g
J 0
(-890 6785);
DISPLAY 0.659574 (-890 6785);
PAINT MONO (-890 6785);
DISPLAY INVISIBLE (-890 6785);
FORCEPROP 1 LAST HDL_POWER PVCCFA_EHV_FIVRA_CPU1
J 1
(-900 6875);
DISPLAY 0.617021 (-900 6875);
PAINT GREEN (-900 6875);
FORCEPROP 2 LAST CDS_LIB logical_power
J 0
(-900 6825);
DISPLAY INVISIBLE (-900 6825);
FORCEPROP 1 LAST PATH I76
J 0
(-850 6850);
DISPLAY 0.872340 (-850 6850);
PAINT AQUA (-850 6850);
DISPLAY INVISIBLE (-850 6850);
FORCEADD Q_CAP..1
(-975 7275);
FORCEPROP 1 LAST PART_NUMBER CH6223MEA01
J 0
(-925 7150);
DISPLAY 0.404255 (-925 7150);
DISPLAY INVISIBLE (-925 7150);
FORCEPROP 1 LAST TOLERANCE 20%
J 0
(-925 7250);
DISPLAY 0.510638 (-925 7250);
FORCEPROP 1 LAST PACK_TYPE C0805
J 0
(-925 7100);
DISPLAY 0.510638 (-925 7100);
FORCEPROP 1 LAST VOLTAGE 16V
J 0
(-925 7300);
DISPLAY 0.510638 (-925 7300);
FORCEPROP 1 LAST VALUE 22UF
J 0
(-925 7350);
DISPLAY 0.510638 (-925 7350);
FORCEPROP 1 LAST MATERIAL X6S
J 0
(-925 7200);
DISPLAY 0.510638 (-925 7200);
FORCEPROP 1 LAST LOCATION PC1682
J 0
(-925 7400);
DISPLAY 0.510638 (-925 7400);
FORCEPROP 1 LASTPIN (-975 7375) $PN 1
J 0
(-965 7355);
DISPLAY 0.787234 (-965 7355);
PAINT MONO (-965 7355);
FORCEPROP 1 LASTPIN (-975 7175) $PN 2
J 0
(-965 7155);
DISPLAY 0.787234 (-965 7155);
PAINT MONO (-965 7155);
FORCEPROP 2 LAST CDS_LIB pure_quanta
J 0
(-975 7275);
DISPLAY INVISIBLE (-975 7275);
FORCEPROP 1 LAST PATH I77
J 0
(-925 7425);
DISPLAY 0.978723 (-925 7425);
PAINT WHITE (-925 7425);
DISPLAY INVISIBLE (-925 7425);
FORCEPROP 0 LAST $SEC 1
J 0
(-925 7425);
DISPLAY 0.680851 (-925 7425);
PAINT MONO (-925 7425);
DISPLAY INVISIBLE (-925 7425);
FORCEPROP 0 LAST CDS_SEC 1
J 0
(-925 7425);
DISPLAY 1.021277 (-925 7425);
DISPLAY INVISIBLE (-925 7425);
FORCEADD Q_CAP..1
(-700 7275);
FORCEPROP 1 LAST PART_NUMBER CH6223MEA01
J 0
(-650 7150);
DISPLAY 0.404255 (-650 7150);
DISPLAY INVISIBLE (-650 7150);
FORCEPROP 1 LAST TOLERANCE 20%
J 0
(-650 7250);
DISPLAY 0.510638 (-650 7250);
FORCEPROP 1 LAST PACK_TYPE C0805
J 0
(-650 7100);
DISPLAY 0.510638 (-650 7100);
FORCEPROP 1 LAST VOLTAGE 16V
J 0
(-650 7300);
DISPLAY 0.510638 (-650 7300);
FORCEPROP 1 LAST MATERIAL X6S
J 0
(-650 7200);
DISPLAY 0.510638 (-650 7200);
FORCEPROP 1 LAST VALUE 22UF
J 0
(-650 7350);
DISPLAY 0.510638 (-650 7350);
FORCEPROP 1 LAST LOCATION PC1683
J 0
(-650 7400);
DISPLAY 0.510638 (-650 7400);
FORCEPROP 1 LASTPIN (-700 7375) $PN 1
J 0
(-690 7355);
DISPLAY 0.787234 (-690 7355);
PAINT MONO (-690 7355);
FORCEPROP 1 LASTPIN (-700 7175) $PN 2
J 0
(-690 7155);
DISPLAY 0.787234 (-690 7155);
PAINT MONO (-690 7155);
FORCEPROP 2 LAST CDS_LIB pure_quanta
J 0
(-700 7275);
DISPLAY INVISIBLE (-700 7275);
FORCEPROP 1 LAST PATH I78
J 0
(-650 7425);
DISPLAY 0.978723 (-650 7425);
PAINT WHITE (-650 7425);
DISPLAY INVISIBLE (-650 7425);
FORCEPROP 0 LAST $SEC 1
J 0
(-650 7425);
DISPLAY 0.680851 (-650 7425);
PAINT MONO (-650 7425);
DISPLAY INVISIBLE (-650 7425);
FORCEPROP 0 LAST CDS_SEC 1
J 0
(-650 7425);
DISPLAY 1.021277 (-650 7425);
DISPLAY INVISIBLE (-650 7425);
FORCEADD UNIVERSAL_GND..1
(-150 6950);
FORCEPROP 3 LASTPIN (-150 7000) SIG_NAME GND\g
J 0
(-140 7010);
DISPLAY 0.659574 (-140 7010);
PAINT MONO (-140 7010);
DISPLAY INVISIBLE (-140 7010);
FORCEPROP 1 LAST HDL_POWER GND
J 1
(-125 6875);
DISPLAY 0.872340 (-125 6875);
PAINT GREEN (-125 6875);
DISPLAY INVISIBLE (-125 6875);
FORCEPROP 2 LAST CDS_LIB logical_power
J 0
(-150 6950);
PAINT MONO (-150 6950);
DISPLAY INVISIBLE (-150 6950);
FORCEPROP 1 LAST PATH I79
J 0
(-75 6950);
DISPLAY 0.872340 (-75 6950);
PAINT AQUA (-75 6950);
DISPLAY INVISIBLE (-75 6950);
FORCEADD OFFPAGE..1
(-7350 3225);
FORCEPROP 2 LAST $XR0 284 
J 0
(-7602 3225);
DISPLAY 0.638298 (-7602 3225);
PAINT MONO (-7602 3225);
FORCEPROP 1 LAST COMMENT_BODY TRUE
J 0
(-7225 3125);
DISPLAY 0.872340 (-7225 3125);
PAINT GREEN (-7225 3125);
DISPLAY INVISIBLE (-7225 3125);
FORCEPROP 1 LAST OFFPAGE TRUE
J 0
(-7025 3100);
DISPLAY 0.872340 (-7025 3100);
PAINT GREEN (-7025 3100);
DISPLAY INVISIBLE (-7025 3100);
FORCEPROP 2 LAST CDS_LIB standard
J 0
(-7350 3225);
DISPLAY INVISIBLE (-7350 3225);
FORCEPROP 2 LAST PATH I8
J 0
(-7600 3275);
DISPLAY 1.021277 (-7600 3275);
DISPLAY INVISIBLE (-7600 3275);
FORCEADD Q_CAP..1
(-425 7275);
FORCEPROP 1 LAST PART_NUMBER CH6223MEA01
J 0
(-375 7150);
DISPLAY 0.404255 (-375 7150);
DISPLAY INVISIBLE (-375 7150);
FORCEPROP 1 LAST TOLERANCE 20%
J 0
(-375 7250);
DISPLAY 0.510638 (-375 7250);
FORCEPROP 1 LAST VALUE 22UF
J 0
(-375 7350);
DISPLAY 0.510638 (-375 7350);
FORCEPROP 1 LAST VOLTAGE 16V
J 0
(-375 7300);
DISPLAY 0.510638 (-375 7300);
FORCEPROP 1 LAST MATERIAL X6S
J 0
(-375 7200);
DISPLAY 0.510638 (-375 7200);
FORCEPROP 1 LAST PACK_TYPE C0805
J 0
(-375 7100);
DISPLAY 0.510638 (-375 7100);
FORCEPROP 1 LAST LOCATION PC1684
J 0
(-375 7400);
DISPLAY 0.510638 (-375 7400);
FORCEPROP 1 LASTPIN (-425 7375) $PN 1
J 0
(-415 7355);
DISPLAY 0.787234 (-415 7355);
PAINT MONO (-415 7355);
FORCEPROP 1 LASTPIN (-425 7175) $PN 2
J 0
(-415 7155);
DISPLAY 0.787234 (-415 7155);
PAINT MONO (-415 7155);
FORCEPROP 2 LAST CDS_LIB pure_quanta
J 0
(-425 7275);
DISPLAY INVISIBLE (-425 7275);
FORCEPROP 1 LAST PATH I80
J 0
(-375 7425);
DISPLAY 0.978723 (-375 7425);
PAINT WHITE (-375 7425);
DISPLAY INVISIBLE (-375 7425);
FORCEPROP 0 LAST $SEC 1
J 0
(-375 7425);
DISPLAY 0.680851 (-375 7425);
PAINT MONO (-375 7425);
DISPLAY INVISIBLE (-375 7425);
FORCEPROP 0 LAST CDS_SEC 1
J 0
(-375 7425);
DISPLAY 1.021277 (-375 7425);
DISPLAY INVISIBLE (-375 7425);
FORCEADD Q_CAPP..1
(-150 7275);
FORCEPROP 1 LAST PART_NUMBER CC72703MD38
J 0
(-100 7100);
DISPLAY 0.617021 (-100 7100);
PAINT BLUE (-100 7100);
DISPLAY INVISIBLE (-100 7100);
FORCEPROP 1 LAST PACK_TYPE THLF
J 0
(-100 7150);
DISPLAY 0.617021 (-100 7150);
PAINT SKYBLUE (-100 7150);
FORCEPROP 1 LAST TOLERANCE 20%
J 0
(-100 7300);
DISPLAY 0.617021 (-100 7300);
PAINT SKYBLUE (-100 7300);
FORCEPROP 1 LAST MATERIAL OSCON
J 0
(-100 7200);
DISPLAY 0.617021 (-100 7200);
PAINT SKYBLUE (-100 7200);
FORCEPROP 1 LAST VALUE 270UF
J 0
(-100 7350);
DISPLAY 0.617021 (-100 7350);
PAINT SKYBLUE (-100 7350);
FORCEPROP 1 LAST VOLTAGE 16V
J 0
(-100 7250);
DISPLAY 0.617021 (-100 7250);
PAINT SKYBLUE (-100 7250);
FORCEPROP 1 LAST LOCATION PC1210
J 0
(-100 7400);
DISPLAY 0.617021 (-100 7400);
PAINT AQUA (-100 7400);
FORCEPROP 1 LASTPIN (-150 7375) $PN 1
J 0
(-140 7360);
DISPLAY 0.617021 (-140 7360);
PAINT MONO (-140 7360);
FORCEPROP 1 LASTPIN (-150 7175) $PN 2
J 0
(-140 7160);
DISPLAY 0.617021 (-140 7160);
PAINT MONO (-140 7160);
FORCEPROP 2 LAST CDS_LIB pure_quanta
J 0
(-150 7275);
DISPLAY INVISIBLE (-150 7275);
FORCEPROP 1 LAST PATH I81
J 0
(-100 7425);
DISPLAY 0.978723 (-100 7425);
DISPLAY INVISIBLE (-100 7425);
FORCEPROP 1 LAST LOCATION PC1210
J 0
(-100 7450);
DISPLAY 1.021277 (-100 7450);
PAINT AQUA (-100 7450);
DISPLAY INVISIBLE (-100 7450);
FORCEPROP 0 LAST $SEC 1
J 0
(-100 7450);
DISPLAY 0.680851 (-100 7450);
PAINT MONO (-100 7450);
DISPLAY INVISIBLE (-100 7450);
FORCEPROP 0 LAST CDS_SEC 1
J 0
(-100 7450);
DISPLAY 1.021277 (-100 7450);
DISPLAY INVISIBLE (-100 7450);
FORCEADD VCC15..1
(-50 7650);
FORCEPROP 3 LASTPIN (-50 7600) SIG_NAME SW_P12V_PVCCFA_EHV_FIVRA_CPU1_R\g
J 0
(-40 7610);
DISPLAY 0.659574 (-40 7610);
PAINT MONO (-40 7610);
DISPLAY INVISIBLE (-40 7610);
FORCEPROP 1 LAST HDL_POWER SW_P12V_PVCCFA_EHV_FIVRA_CPU1_R
J 1
(0 7700);
DISPLAY 0.617021 (0 7700);
PAINT GREEN (0 7700);
FORCEPROP 2 LAST CDS_LIB logical_power
J 0
(-50 7650);
DISPLAY INVISIBLE (-50 7650);
FORCEPROP 1 LAST PATH I82
J 0
(0 7675);
DISPLAY 0.872340 (0 7675);
PAINT AQUA (0 7675);
DISPLAY INVISIBLE (0 7675);
FORCEADD OFFPAGE..1
(-7350 3725);
FORCEPROP 2 LAST $XR6 290 
J 0
(-8322 3725);
DISPLAY 0.638298 (-8322 3725);
PAINT MONO (-8322 3725);
FORCEPROP 2 LAST $XR5 289 
J 0
(-8202 3725);
DISPLAY 0.638298 (-8202 3725);
PAINT MONO (-8202 3725);
FORCEPROP 2 LAST $XR4 288 
J 0
(-8082 3725);
DISPLAY 0.638298 (-8082 3725);
PAINT MONO (-8082 3725);
FORCEPROP 2 LAST $XR3 287 
J 0
(-7962 3725);
DISPLAY 0.638298 (-7962 3725);
PAINT MONO (-7962 3725);
FORCEPROP 2 LAST $XR2 286 
J 0
(-7842 3725);
DISPLAY 0.638298 (-7842 3725);
PAINT MONO (-7842 3725);
FORCEPROP 2 LAST $XR1 285 
J 0
(-7722 3725);
DISPLAY 0.638298 (-7722 3725);
PAINT MONO (-7722 3725);
FORCEPROP 2 LAST $XR0 284 
J 0
(-7602 3725);
DISPLAY 0.638298 (-7602 3725);
PAINT MONO (-7602 3725);
FORCEPROP 1 LAST COMMENT_BODY TRUE
J 0
(-7225 3625);
DISPLAY 0.872340 (-7225 3625);
PAINT GREEN (-7225 3625);
DISPLAY INVISIBLE (-7225 3625);
FORCEPROP 1 LAST OFFPAGE TRUE
J 0
(-7025 3600);
DISPLAY 0.872340 (-7025 3600);
PAINT GREEN (-7025 3600);
DISPLAY INVISIBLE (-7025 3600);
FORCEPROP 2 LAST CDS_LIB standard
J 0
(-7350 3725);
DISPLAY INVISIBLE (-7350 3725);
FORCEPROP 2 LAST PATH I9
J 0
(-7600 3775);
DISPLAY 1.021277 (-7600 3775);
DISPLAY INVISIBLE (-7600 3775);
FORCEADD DNS..1
(-7825 3300);
PAINT RED (-7825 3300);
FORCEPROP 1 LAST COMMENT_BODY TRUE
R 1
J 0
(-7750 3075);
DISPLAY 0.872340 (-7750 3075);
PAINT GREEN (-7750 3075);
DISPLAY INVISIBLE (-7750 3075);
FORCEPROP 2 LAST CDS_LIB mstr_misc
J 0
(-7825 3300);
PAINT MONO (-7825 3300);
DISPLAY INVISIBLE (-7825 3300);
FORCEADD DNS..1
(-7800 6100);
PAINT RED (-7800 6100);
FORCEPROP 1 LAST COMMENT_BODY TRUE
R 1
J 0
(-7725 5875);
DISPLAY 0.872340 (-7725 5875);
PAINT GREEN (-7725 5875);
DISPLAY INVISIBLE (-7725 5875);
FORCEPROP 2 LAST CDS_LIB mstr_misc
J 0
(-7800 6100);
PAINT MONO (-7800 6100);
DISPLAY INVISIBLE (-7800 6100);
FORCEADD QUANTA_TITLE_BLOCK_C..1
(850 1900);
FORCEPROP 0 LAST CDS_CON_LAST_MODIFIED Fri Aug 25 14:05:01 2023
J 0
(-1035 1915);
DISPLAY INVISIBLE (-1035 1915);
FORCEPROP 1 LAST CUSTOM_TXT_CDS <CON_LAST_MODIFIED>
J 0
(-1035 1915);
DISPLAY 0.978723 (-1035 1915);
FORCEPROP 2 LAST CUSTOM_TXT_CDS <XR_PAGE_TITLE>
J 0
(-7040 7150);
DISPLAY 0.638298 (-7040 7150);
PAINT PINK (-7040 7150);
DISPLAY INVISIBLE (-7040 7150);
FORCEPROP 1 LAST CUSTOM_TXT_CDS <NAME_2>
J 0
(-2325 1950);
FORCEPROP 1 LAST CUSTOM_TXT_CDS <NAME_1>
J 0
(-2325 2075);
FORCEPROP 1 LAST CUSTOM_TXT_CDS <Q_NUMBER>
J 0
(-553 2003);
DISPLAY 1.212766 (-553 2003);
FORCEPROP 1 LAST CUSTOM_TXT_CDS <Q_PROJ>
J 0
(-1532 2002);
DISPLAY 1.212766 (-1532 2002);
FORCEPROP 1 LAST CUSTOM_TXT_CDS <Q_REV>
J 0
(666 2003);
DISPLAY 1.212766 (666 2003);
FORCEPROP 1 LAST CUSTOM_TXT_CDS <CON_PAGE_NUM> OF <CON_TOTAL_PAGES>
J 0
(404 1918);
DISPLAY 0.978723 (404 1918);
FORCEPROP 1 LAST Q_TITLE VCCFA_EHV_FIVRA CPU1 VR PHASE 3&4(7/7)
J 0
(-8450 1950);
DISPLAY 2.446809 (-8450 1950);
PAINT GREEN (-8450 1950);
FORCEPROP 1 LAST Q_DEPT 
J 1
(-2913 1949);
DISPLAY 1.957447 (-2913 1949);
PAINT GREEN (-2913 1949);
FORCEPROP 2 LAST CDS_XR_PAGE_TITLE CR-290 : @S9S_MB_2U_LIB.S9S_MB_2U(SCH_1):PAGE290
J 0
(-7040 7150);
DISPLAY 0.638298 (-7040 7150);
PAINT PINK (-7040 7150);
DISPLAY INVISIBLE (-7040 7150);
FORCEPROP 2 LAST CDS_LIB pure_quanta
J 0
(850 1900);
DISPLAY INVISIBLE (850 1900);
FORCEPROP 1 LAST CDS_LMAN_SYM_OUTLINE -9475,6775,100,-125
J 0
(850 1900);
DISPLAY 0.468085 (850 1900);
PAINT GREEN (850 1900);
DISPLAY INVISIBLE (850 1900);
FORCEPROP 2 LAST PAGE_BORDER TRUE
J 0
(-7040 7150);
DISPLAY 0.638298 (-7040 7150);
PAINT PINK (-7040 7150);
DISPLAY INVISIBLE (-7040 7150);
FORCEPROP 1 LAST COMMENT_BODY TRUE
J 0
(862 1887);
DISPLAY 0.978723 (862 1887);
PAINT GREEN (862 1887);
DISPLAY INVISIBLE (862 1887);
WIRE 16 -1 (-7325 4950)(-7325 4875);
WIRE 16 -1 (-7325 7750)(-7325 7675);
WIRE 16 -1 (-900 3975)(-900 3825);
WIRE 16 -1 (-3200 5050)(-3200 4975);
WIRE 16 -1 (-3200 7850)(-3200 7775);
WIRE 16 -1 (-2075 7625)(-2075 7500);
WIRE 16 -1 (375 5450)(375 5400);
WIRE 16 -1 (-900 6775)(-900 6625);
WIRE 16 -1 (-50 7600)(-50 7500);
WIRE 16 -1 (-7825 3225)(-7825 3150);
WIRE 16 -1 (-7875 3625)(-7875 3575);
WIRE 16 -1 (-7875 3625)(-7150 3625);
WIRE 16 -1 (-7800 6025)(-7800 5950);
WIRE 16 -1 (-7875 6425)(-7875 6375);
WIRE 16 -1 (-7875 6425)(-7150 6425);
WIRE 16 -1 (-7325 4175)(-7325 4075);
WIRE 16 -1 (-6800 4575)(-6800 4475);
WIRE 16 -1 (-5150 3225)(-5150 3150);
WIRE 16 -1 (-5150 3275)(-5150 3225);
WIRE 16 -1 (-5400 3225)(-5150 3225);
WIRE 16 -1 (-7325 6975)(-7325 6875);
WIRE 16 -1 (-6800 7375)(-6800 7275);
WIRE 16 -1 (-5150 6025)(-5150 5950);
WIRE 16 -1 (-5150 6075)(-5150 6025);
WIRE 16 -1 (-5400 6025)(-5150 6025);
WIRE 16 -1 (-3200 4400)(-3200 4475);
WIRE 16 -1 (-900 3300)(-900 3400);
WIRE 16 -1 (-3200 7225)(-3200 7275);
WIRE 16 -1 (-2075 7100)(-2075 7200);
WIRE 16 -1 (-900 6100)(-900 6200);
WIRE 16 -1 (375 4975)(375 4875);
WIRE 16 -1 (-75 4975)(375 4975);
WIRE 16 -1 (375 5075)(375 4975);
WIRE 16 -1 (-150 7075)(-150 7000);
WIRE 16 -1 (-425 7075)(-150 7075);
WIRE 16 -1 (-150 7175)(-150 7075);
WIRE 16 -1 (-1625 5075)(-1625 4975);
WIRE 16 -1 (-1625 4975)(-1100 4975);
WIRE 16 -1 (-1100 4975)(-1100 5075);
WIRE 16 -1 (-1100 4975)(-575 4975);
WIRE 16 -1 (-575 5075)(-575 4975);
WIRE 16 -1 (-75 4975)(-575 4975);
WIRE 16 -1 (-75 5075)(-75 4975);
WIRE 16 -1 (-1625 5275)(-1625 5400);
WIRE 16 -1 (-1625 5400)(-1100 5400);
WIRE 16 -1 (-1100 5400)(-1100 5275);
WIRE 16 -1 (-1100 5400)(-575 5400);
WIRE 16 -1 (-575 5275)(-575 5400);
WIRE 16 -1 (-75 5400)(-575 5400);
WIRE 16 -1 (-75 5275)(-75 5400);
WIRE 16 -1 (-75 5400)(375 5400);
WIRE 16 -1 (375 5400)(375 5275);
WIRE 16 -1 (-425 7175)(-425 7075);
WIRE 16 -1 (-700 7075)(-425 7075);
WIRE 16 -1 (-700 7175)(-700 7075);
WIRE 16 -1 (-975 7075)(-700 7075);
WIRE 16 -1 (-975 7175)(-975 7075);
WIRE 16 -1 (-1275 7075)(-975 7075);
WIRE 16 -1 (-1275 7175)(-1275 7075);
WIRE 16 -1 (-150 7500)(-150 7375);
WIRE 16 -1 (-50 7500)(-150 7500);
WIRE 16 -1 (-425 7375)(-425 7500);
WIRE 16 -1 (-425 7500)(-150 7500);
WIRE 16 -1 (-700 7375)(-700 7500);
WIRE 16 -1 (-700 7500)(-425 7500);
WIRE 16 -1 (-975 7375)(-975 7500);
WIRE 16 -1 (-975 7500)(-700 7500);
WIRE 16 -1 (-1275 7375)(-1275 7500);
WIRE 16 -1 (-1275 7500)(-975 7500);
WIRE 16 -1 (-1550 7500)(-1275 7500);
WIRE 16 -1 (-2825 6375)(-3000 6375);
WIRE 16 -1 (-2825 6625)(-2825 6375);
WIRE 16 -1 (-2825 6625)(-3000 6625);
WIRE 16 -1 (-1200 6525)(-1200 6625);
WIRE 16 -1 (-900 6625)(-1200 6625);
WIRE 16 -1 (-1625 6625)(-1625 6525);
WIRE 16 -1 (-1625 6625)(-1200 6625);
WIRE 16 -1 (-2050 6625)(-2825 6625);
WIRE 16 -1 (-2050 6525)(-2050 6625);
WIRE 16 -1 (-2050 6625)(-1625 6625);
WIRE 16 -1 (-1200 6325)(-1200 6200);
WIRE 16 -1 (-900 6200)(-1200 6200);
WIRE 16 -1 (-1625 6200)(-1625 6325);
WIRE 16 -1 (-1200 6200)(-1625 6200);
WIRE 16 -1 (-2050 6200)(-1625 6200);
WIRE 16 -1 (-2050 6325)(-2050 6200);
WIRE 16 -1 (-2075 7400)(-2075 7500);
WIRE 16 -1 (-2075 7500)(-1750 7500);
WIRE 16 -1 (-3350 7625)(-3350 7775);
WIRE 16 -1 (-3200 7775)(-3350 7775);
WIRE 16 -1 (-3800 7625)(-3800 7775);
WIRE 16 -1 (-3350 7775)(-3800 7775);
WIRE 16 -1 (-4200 7775)(-4200 7625);
WIRE 16 -1 (-4200 7775)(-3800 7775);
WIRE 16 -1 (-5225 7225)(-5400 7225);
WIRE 16 -1 (-5400 7275)(-5225 7275);
WIRE 16 -1 (-5225 7275)(-5225 7225);
WIRE 16 -1 (-4600 7625)(-4600 7775);
WIRE 16 -1 (-4600 7775)(-4200 7775);
WIRE 16 -1 (-5000 7625)(-5000 7775);
WIRE 16 -1 (-5000 7775)(-4600 7775);
WIRE 16 -1 (-5225 7775)(-5225 7275);
WIRE 16 -1 (-5225 7775)(-5000 7775);
WIRE 16 -1 (-3350 7425)(-3350 7275);
WIRE 16 -1 (-3200 7275)(-3350 7275);
WIRE 16 -1 (-3800 7425)(-3800 7275);
WIRE 16 -1 (-3350 7275)(-3800 7275);
WIRE 16 -1 (-4200 7425)(-4200 7275);
WIRE 16 -1 (-4200 7275)(-3800 7275);
WIRE 16 -1 (-4600 7425)(-4600 7275);
WIRE 16 -1 (-4200 7275)(-4600 7275);
WIRE 16 -1 (-5000 7275)(-4600 7275);
WIRE 16 -1 (-5000 7425)(-5000 7275);
WIRE 16 -1 (-3350 4825)(-3350 4975);
WIRE 16 -1 (-3200 4975)(-3350 4975);
WIRE 16 -1 (-3800 4825)(-3800 4975);
WIRE 16 -1 (-3350 4975)(-3800 4975);
WIRE 16 -1 (-4200 4975)(-4200 4825);
WIRE 16 -1 (-4200 4975)(-3800 4975);
WIRE 16 -1 (-5225 4425)(-5400 4425);
WIRE 16 -1 (-5400 4475)(-5225 4475);
WIRE 16 -1 (-5225 4475)(-5225 4425);
WIRE 16 -1 (-4600 4825)(-4600 4975);
WIRE 16 -1 (-4600 4975)(-4200 4975);
WIRE 16 -1 (-5000 4825)(-5000 4975);
WIRE 16 -1 (-5000 4975)(-4600 4975);
WIRE 16 -1 (-5225 4975)(-5225 4475);
WIRE 16 -1 (-5225 4975)(-5000 4975);
WIRE 16 -1 (-3200 4475)(-3350 4475);
WIRE 16 -1 (-3350 4625)(-3350 4475);
WIRE 16 -1 (-3800 4625)(-3800 4475);
WIRE 16 -1 (-3350 4475)(-3800 4475);
WIRE 16 -1 (-4200 4625)(-4200 4475);
WIRE 16 -1 (-4200 4475)(-3800 4475);
WIRE 16 -1 (-4200 4475)(-4600 4475);
WIRE 16 -1 (-4600 4625)(-4600 4475);
WIRE 16 -1 (-5000 4475)(-4600 4475);
WIRE 16 -1 (-5000 4625)(-5000 4475);
WIRE 16 -1 (-1200 3725)(-1200 3825);
WIRE 16 -1 (-900 3825)(-1200 3825);
WIRE 16 -1 (-2825 3575)(-3000 3575);
WIRE 16 -1 (-1625 3825)(-1625 3725);
WIRE 16 -1 (-1625 3825)(-1200 3825);
WIRE 16 -1 (-2150 3725)(-2150 3825);
WIRE 16 -1 (-1625 3825)(-2150 3825);
WIRE 16 -1 (-2825 3825)(-2825 3575);
WIRE 16 -1 (-3000 3825)(-2825 3825);
WIRE 16 -1 (-2825 3825)(-2150 3825);
WIRE 16 -1 (-1200 3525)(-1200 3400);
WIRE 16 -1 (-900 3400)(-1200 3400);
WIRE 16 -1 (-1625 3525)(-1625 3400);
WIRE 16 -1 (-1200 3400)(-1625 3400);
WIRE 16 -1 (-2150 3400)(-1625 3400);
WIRE 16 -1 (-2150 3525)(-2150 3400);
WIRE 16 -1 (-5400 6375)(-3200 6375);
FORCEPROP 2 LAST SIG_NAME PVCCFA_EHV_FIVRA_CPU1_VOS3
J 0
(-5210 6385);
DISPLAY 0.617021 (-5210 6385);
WIRE 16 -1 (-3375 6725)(-3375 6800);
WIRE 16 -1 (-5400 6725)(-3375 6725);
FORCEPROP 2 LAST SIG_NAME SW_PVCCFA_EHV_FIVRA_CPU1_BOOTR3
J 0
(-5210 6735);
DISPLAY 0.617021 (-5210 6735);
WIRE 16 -1 (-5400 6625)(-3200 6625);
FORCEPROP 2 LAST SIG_NAME SW_PVCCFA_EHV_FIVRA_CPU1_SW3
J 0
(-5210 6635);
DISPLAY 0.617021 (-5210 6635);
WIRE 16 -1 (-5400 3825)(-3200 3825);
FORCEPROP 2 LAST SIG_NAME SW_PVCCFA_EHV_FIVRA_CPU1_SW4
J 0
(-5210 3835);
DISPLAY 0.617021 (-5210 3835);
WIRE 16 -1 (-5400 3575)(-3200 3575);
FORCEPROP 2 LAST SIG_NAME PVCCFA_EHV_FIVRA_CPU1_VOS4
J 0
(-5210 3585);
DISPLAY 0.617021 (-5210 3585);
WIRE 16 -1 (-3375 4275)(-3375 4200);
WIRE 16 -1 (-4200 4275)(-3375 4275);
FORCEPROP 2 LAST SIG_NAME SW_PVCCFA_EHV_FIVRA_CPU1_BOOT4_R
J 0
(-4010 4285);
DISPLAY 0.617021 (-4010 4285);
WIRE 16 -1 (-3375 7075)(-3375 7000);
WIRE 16 -1 (-4200 7075)(-3375 7075);
FORCEPROP 2 LAST SIG_NAME SW_PVCCFA_EHV_FIVRA_CPU1_BOOT3_R
J 0
(-4010 7085);
DISPLAY 0.617021 (-4010 7085);
WIRE 16 -1 (-3375 3925)(-3375 4000);
WIRE 16 -1 (-5400 3925)(-3375 3925);
FORCEPROP 2 LAST SIG_NAME SW_PVCCFA_EHV_FIVRA_CPU1_BOOTR4
J 0
(-5210 3935);
DISPLAY 0.617021 (-5210 3935);
WIRE 16 -1 (-5250 7075)(-4400 7075);
WIRE 16 -1 (-5250 6975)(-5250 7075);
FORCEPROP 2 LAST SIG_NAME SW_PVCCFA_EHV_FIVRA_CPU1_BOOT3
J 0
(-5460 7085);
DISPLAY 0.617021 (-5460 7085);
WIRE 16 -1 (-5400 6975)(-5250 6975);
WIRE 16 -1 (-5150 6175)(-5400 6175);
WIRE 16 -1 (-5400 6125)(-5150 6125);
WIRE 16 -1 (-5150 6125)(-5150 6175);
WIRE 16 -1 (-5150 6125)(-5150 6075);
WIRE 16 -1 (-5400 6075)(-5150 6075);
WIRE 16 -1 (-7325 7675)(-7325 7575);
WIRE 16 -1 (-6800 7675)(-7325 7675);
WIRE 16 -1 (-6800 7575)(-6800 7675);
WIRE 16 -1 (-6400 7675)(-6800 7675);
WIRE 16 -1 (-6400 7275)(-6250 7275);
WIRE 16 -1 (-6400 7275)(-6400 7675);
WIRE 16 -1 (-6250 6775)(-6400 6775);
WIRE 16 -1 (-6400 6975)(-6400 6775);
WIRE 16 -1 (-6250 6975)(-6400 6975);
WIRE 16 -1 (-7325 7175)(-7325 7275);
WIRE 16 -1 (-7325 7275)(-7325 7375);
WIRE 16 -1 (-7075 7275)(-7325 7275);
WIRE 16 -1 (-6400 6975)(-7075 6975);
FORCEPROP 0 LAST CDS_PHYS_NET_NAME PVCCFA_EHV_FIVRA_CPU1_VDD3
J 0
(-7010 7015);
PAINT MONO (-7010 7015);
DISPLAY INVISIBLE (-7010 7015);
FORCEPROP 2 LAST SIG_NAME PVCCFA_EHV_FIVRA_CPU1_VDD3
J 0
(-7035 6985);
DISPLAY 0.617021 (-7035 6985);
WIRE 16 -1 (-7075 6975)(-7075 7275);
WIRE 16 -1 (-6250 6625)(-7275 6625);
FORCEPROP 2 LAST SIG_NAME PVCCFA_EHV_FIVRA_CPU1_IMON3
J 0
(-7210 6635);
DISPLAY 0.617021 (-7210 6635);
WIRE 16 -1 (-6400 6425)(-6950 6425);
WIRE 16 -1 (-7275 6525)(-6400 6525);
FORCEPROP 2 LAST SIG_NAME PVCCIN_CPU1_VREF
J 0
(-7210 6535);
DISPLAY 0.617021 (-7210 6535);
WIRE 16 -1 (-6400 6525)(-6250 6525);
WIRE 16 -1 (-6400 6525)(-6400 6425);
WIRE 16 -1 (-7325 4875)(-7325 4775);
WIRE 16 -1 (-6800 4875)(-7325 4875);
WIRE 16 -1 (-6800 4775)(-6800 4875);
WIRE 16 -1 (-6400 4875)(-6800 4875);
WIRE 16 -1 (-6400 4475)(-6250 4475);
WIRE 16 -1 (-6400 4475)(-6400 4875);
WIRE 16 -1 (-6250 6125)(-7275 6125);
FORCEPROP 2 LAST SIG_NAME PVCCFA_EHV_FIVRA_CPU1_BTSEN
J 0
(-7210 6135);
DISPLAY 0.617021 (-7210 6135);
WIRE 16 -1 (-6250 6025)(-7275 6025);
FORCEPROP 2 LAST SIG_NAME PVCCFA_EHV_FIVRA_CPU1_PWM3
J 0
(-7210 6035);
DISPLAY 0.617021 (-7210 6035);
WIRE 16 -1 (-6250 3975)(-6400 3975);
WIRE 16 -1 (-6400 4175)(-6400 3975);
WIRE 16 -1 (-6250 4175)(-6400 4175);
WIRE 16 -1 (-6400 4175)(-7075 4175);
FORCEPROP 0 LAST CDS_PHYS_NET_NAME PVCCFA_EHV_FIVRA_CPU1_VDD4
J 0
(-7010 4215);
PAINT MONO (-7010 4215);
DISPLAY INVISIBLE (-7010 4215);
FORCEPROP 2 LAST SIG_NAME PVCCFA_EHV_FIVRA_CPU1_VDD4
J 0
(-7035 4185);
DISPLAY 0.617021 (-7035 4185);
WIRE 16 -1 (-7075 4175)(-7075 4475);
WIRE 16 -1 (-7325 4475)(-7325 4575);
WIRE 16 -1 (-7075 4475)(-7325 4475);
WIRE 16 -1 (-7325 4375)(-7325 4475);
WIRE 16 -1 (-5250 4275)(-4400 4275);
WIRE 16 -1 (-5250 4175)(-5250 4275);
FORCEPROP 2 LAST SIG_NAME SW_PVCCFA_EHV_FIVRA_CPU1_BOOT4
J 0
(-5460 4285);
DISPLAY 0.617021 (-5460 4285);
WIRE 16 -1 (-5400 4175)(-5250 4175);
WIRE 16 -1 (-5150 3375)(-5400 3375);
WIRE 16 -1 (-5400 3325)(-5150 3325);
WIRE 16 -1 (-5150 3325)(-5150 3375);
WIRE 16 -1 (-5150 3325)(-5150 3275);
WIRE 16 -1 (-5400 3275)(-5150 3275);
WIRE 16 -1 (-6250 3225)(-7300 3225);
FORCEPROP 2 LAST SIG_NAME PVCCFA_EHV_FIVRA_CPU1_PWM4
J 0
(-7235 3235);
DISPLAY 0.617021 (-7235 3235);
WIRE 16 -1 (-6250 3325)(-7300 3325);
FORCEPROP 2 LAST SIG_NAME PVCCFA_EHV_FIVRA_CPU1_BTSEN
J 0
(-7235 3335);
DISPLAY 0.617021 (-7235 3335);
WIRE 16 -1 (-6250 3825)(-7300 3825);
FORCEPROP 2 LAST SIG_NAME PVCCFA_EHV_FIVRA_CPU1_IMON4
J 0
(-7235 3835);
DISPLAY 0.617021 (-7235 3835);
WIRE 16 -1 (-6400 3625)(-6950 3625);
WIRE 16 -1 (-7300 3725)(-6400 3725);
FORCEPROP 2 LAST SIG_NAME PVCCIN_CPU1_VREF
J 0
(-7235 3735);
DISPLAY 0.617021 (-7235 3735);
WIRE 16 -1 (-6400 3725)(-6250 3725);
WIRE 16 -1 (-6400 3725)(-6400 3625);
WIRE 16 -1 (-7800 6325)(-7800 6225);
WIRE 16 -1 (-7800 6325)(-6250 6325);
FORCEPROP 2 LAST SIG_NAME PVCCFA_EHV_FIVRA_CPU1_LSET3
J 0
(-7210 6335);
DISPLAY 0.617021 (-7210 6335);
WIRE 16 -1 (-7825 3525)(-7825 3425);
WIRE 16 -1 (-7825 3525)(-6250 3525);
FORCEPROP 2 LAST SIG_NAME PVCCFA_EHV_FIVRA_CPU1_LSET4
J 0
(-7235 3535);
DISPLAY 0.617021 (-7235 3535);
DOT 1 (-6400 3725);
DOT 1 (-6400 4175);
DOT 1 (-5150 3275);
DOT 1 (-5150 3225);
DOT 1 (-5150 3325);
DOT 1 (-7325 4475);
DOT 1 (-7325 4875);
DOT 1 (-6800 4875);
DOT 1 (-7325 7275);
DOT 1 (-7325 7675);
DOT 1 (-6800 7675);
DOT 1 (-6400 6525);
DOT 1 (-6400 6975);
DOT 1 (-5225 4475);
DOT 1 (-5000 4975);
DOT 1 (-5150 6025);
DOT 1 (-5150 6075);
DOT 1 (-5150 6125);
DOT 1 (-4600 4475);
DOT 1 (-4600 4975);
DOT 1 (-4200 4975);
DOT 1 (-4200 4475);
DOT 1 (-3800 4475);
DOT 1 (-3800 4975);
DOT 1 (-5225 7275);
DOT 1 (-5000 7775);
DOT 1 (-4600 7275);
DOT 1 (-4200 7275);
DOT 1 (-3800 7275);
DOT 1 (-4600 7775);
DOT 1 (-4200 7775);
DOT 1 (-3800 7775);
DOT 1 (-2825 3825);
DOT 1 (-2150 3825);
DOT 1 (-1625 3400);
DOT 1 (-1200 3400);
DOT 1 (-1625 3825);
DOT 1 (-1200 3825);
DOT 1 (-3350 4475);
DOT 1 (-3350 4975);
DOT 1 (-3350 7275);
DOT 1 (-2825 6625);
DOT 1 (-3350 7775);
DOT 1 (-2050 6625);
DOT 1 (-2075 7500);
DOT 1 (-1100 4975);
DOT 1 (-1100 5400);
DOT 1 (-1625 6200);
DOT 1 (-1200 6200);
DOT 1 (-575 4975);
DOT 1 (-575 5400);
DOT 1 (-75 4975);
DOT 1 (-75 5400);
DOT 1 (375 4975);
DOT 1 (375 5400);
DOT 1 (-1625 6625);
DOT 1 (-1200 6625);
DOT 1 (-1275 7500);
DOT 1 (-975 7075);
DOT 1 (-975 7500);
DOT 1 (-700 7075);
DOT 1 (-700 7500);
DOT 1 (-425 7075);
DOT 1 (-425 7500);
DOT 1 (-150 7075);
DOT 1 (-150 7500);
FORCENOTE
20211013 MODIFY FOR GT
(-8400 8400) 0;
DISPLAY LEFT (-8400 8400);
DISPLAY 1.595745 (-8400 8400);
PAINT PINK (-8400 8400);
FORCENOTE
PVCCFA_EHV_FIVRA_CPU1_PHASE4
(-6600 5000) 0;
DISPLAY LEFT (-6600 5000);
DISPLAY 1.021277 (-6600 5000);
PAINT WHITE (-6600 5000);
FORCENOTE
PVCCFA_EHV_FIVRA_CPU1_PHASE3
(-6625 7725) 0;
DISPLAY LEFT (-6625 7725);
DISPLAY 1.021277 (-6625 7725);
PAINT WHITE (-6625 7725);
FORCENOTE
ISAT = 90A @ 100C
(-2800 4000) 0;
DISPLAY LEFT (-2800 4000);
DISPLAY 1.021277 (-2800 4000);
FORCENOTE
10.0*7.5*12.0
(-2800 4075) 0;
DISPLAY LEFT (-2800 4075);
DISPLAY 1.021277 (-2800 4075);
FORCENOTE
DCR = 0.103M OHM
(-2800 3925) 0;
DISPLAY LEFT (-2800 3925);
DISPLAY 1.021277 (-2800 3925);
FORCENOTE
PG2323.131HLT
(-2800 4150) 0;
DISPLAY LEFT (-2800 4150);
DISPLAY 1.021277 (-2800 4150);
FORCENOTE
ISAT = 90A @ 100C
(-2825 6800) 0;
DISPLAY LEFT (-2825 6800);
DISPLAY 1.021277 (-2825 6800);
FORCENOTE
PG2323.131HLT
(-2825 6950) 0;
DISPLAY LEFT (-2825 6950);
DISPLAY 1.021277 (-2825 6950);
FORCENOTE
10.0*7.5*12.0
(-2825 6875) 0;
DISPLAY LEFT (-2825 6875);
DISPLAY 1.021277 (-2825 6875);
FORCENOTE
DCR = 0.103M OHM
(-2825 6725) 0;
DISPLAY LEFT (-2825 6725);
DISPLAY 1.021277 (-2825 6725);
FORCENOTE
ISAT = 13A @ 100C
(-1475 7675) 0;
DISPLAY LEFT (-1475 7675);
DISPLAY 0.808511 (-1475 7675);
FORCENOTE
DCR = 0.12M OHM
(-1475 7600) 0;
DISPLAY LEFT (-1475 7600);
DISPLAY 0.808511 (-1475 7600);
FORCENOTE
HCBS4545-101
(-1475 7825) 0;
DISPLAY LEFT (-1475 7825);
DISPLAY 0.808511 (-1475 7825);
FORCENOTE
4.5*4.5*4.5
(-1475 7750) 0;
DISPLAY LEFT (-1475 7750);
DISPLAY 0.808511 (-1475 7750);
FORCENOTE
ESR=9.5M OHM
(-100 7050) 0;
DISPLAY LEFT (-100 7050);
DISPLAY 0.638298 (-100 7050);
QUIT
